(kicad_sch (version 20230121) (generator eeschema)

  (paper "A3")

  (title_block
    (title "ECP5 - Datacenter Secure Control Module (DC-SCM)")
    (date "2024-07-15")
    (rev "1.2.1")
  )

  (junction (at 313.69 83.82) (diameter 0) (color 0 0 0 0)
  )
  (junction (at 312.42 36.83) (diameter 0) (color 0 0 0 0)
  )
  (junction (at 396.24 83.82) (diameter 0) (color 0 0 0 0)
  )
  (junction (at 190.5 53.34) (diameter 0) (color 0 0 0 0)
  )
  (junction (at 364.49 143.51) (diameter 0) (color 0 0 0 0)
  )
  (junction (at 372.11 132.08) (diameter 0) (color 0 0 0 0)
  )
  (junction (at 314.96 223.52) (diameter 0) (color 0 0 0 0)
  )
  (junction (at 353.06 144.78) (diameter 0) (color 0 0 0 0)
  )
  (junction (at 372.11 234.95) (diameter 0) (color 0 0 0 0)
  )
  (junction (at 199.39 53.34) (diameter 0) (color 0 0 0 0)
  )
  (junction (at 364.49 179.07) (diameter 0) (color 0 0 0 0)
  )
  (junction (at 119.38 149.86) (diameter 0) (color 0 0 0 0)
  )
  (junction (at 209.55 127) (diameter 0) (color 0 0 0 0)
  )
  (junction (at 353.06 199.39) (diameter 0) (color 0 0 0 0)
  )
  (junction (at 158.75 53.34) (diameter 0) (color 0 0 0 0)
  )
  (junction (at 363.22 83.82) (diameter 0) (color 0 0 0 0)
  )
  (junction (at 381 179.07) (diameter 0) (color 0 0 0 0)
  )
  (junction (at 180.34 127) (diameter 0) (color 0 0 0 0)
  )
  (junction (at 379.73 104.14) (diameter 0) (color 0 0 0 0)
  )
  (junction (at 372.11 152.4) (diameter 0) (color 0 0 0 0)
  )
  (junction (at 350.52 49.53) (diameter 0) (color 0 0 0 0)
  )
  (junction (at 314.96 179.07) (diameter 0) (color 0 0 0 0)
  )
  (junction (at 187.96 142.24) (diameter 0) (color 0 0 0 0)
  )
  (junction (at 389.89 36.83) (diameter 0) (color 0 0 0 0)
  )
  (junction (at 396.24 179.07) (diameter 0) (color 0 0 0 0)
  )
  (junction (at 314.96 132.08) (diameter 0) (color 0 0 0 0)
  )
  (junction (at 365.76 48.26) (diameter 0) (color 0 0 0 0)
  )
  (junction (at 372.11 199.39) (diameter 0) (color 0 0 0 0)
  )
  (junction (at 90.17 226.06) (diameter 0) (color 0 0 0 0)
  )
  (junction (at 157.48 142.24) (diameter 0) (color 0 0 0 0)
  )
  (junction (at 238.76 273.05) (diameter 0) (color 0 0 0 0)
  )
  (junction (at 187.96 127) (diameter 0) (color 0 0 0 0)
  )
  (junction (at 209.55 53.34) (diameter 0) (color 0 0 0 0)
  )
  (junction (at 40.64 40.64) (diameter 0) (color 0 0 0 0)
  )
  (junction (at 351.79 96.52) (diameter 0) (color 0 0 0 0)
  )
  (junction (at 152.4 83.82) (diameter 0) (color 0 0 0 0)
  )
  (junction (at 382.27 36.83) (diameter 0) (color 0 0 0 0)
  )
  (junction (at 382.27 57.15) (diameter 0) (color 0 0 0 0)
  )
  (junction (at 198.12 127) (diameter 0) (color 0 0 0 0)
  )
  (junction (at 86.36 127) (diameter 0) (color 0 0 0 0)
  )
  (junction (at 92.71 228.6) (diameter 0) (color 0 0 0 0)
  )
  (junction (at 73.66 138.43) (diameter 0) (color 0 0 0 0)
  )
  (junction (at 370.84 83.82) (diameter 0) (color 0 0 0 0)
  )
  (junction (at 370.84 95.25) (diameter 0) (color 0 0 0 0)
  )
  (junction (at 238.76 49.53) (diameter 0) (color 0 0 0 0)
  )
  (junction (at 90.17 209.55) (diameter 0) (color 0 0 0 0)
  )
  (junction (at 364.49 190.5) (diameter 0) (color 0 0 0 0)
  )
  (junction (at 372.11 223.52) (diameter 0) (color 0 0 0 0)
  )
  (junction (at 186.69 64.77) (diameter 0) (color 0 0 0 0)
  )
  (junction (at 387.35 83.82) (diameter 0) (color 0 0 0 0)
  )
  (junction (at 158.75 58.42) (diameter 0) (color 0 0 0 0)
  )
  (junction (at 238.76 238.76) (diameter 0) (color 0 0 0 0)
  )
  (junction (at 80.01 127) (diameter 0) (color 0 0 0 0)
  )
  (junction (at 379.73 83.82) (diameter 0) (color 0 0 0 0)
  )
  (junction (at 36.83 69.85) (diameter 0) (color 0 0 0 0)
  )
  (junction (at 364.49 132.08) (diameter 0) (color 0 0 0 0)
  )
  (junction (at 388.62 223.52) (diameter 0) (color 0 0 0 0)
  )
  (junction (at 80.01 138.43) (diameter 0) (color 0 0 0 0)
  )
  (junction (at 372.11 243.84) (diameter 0) (color 0 0 0 0)
  )
  (junction (at 350.52 57.15) (diameter 0) (color 0 0 0 0)
  )
  (junction (at 40.64 43.18) (diameter 0) (color 0 0 0 0)
  )
  (junction (at 397.51 223.52) (diameter 0) (color 0 0 0 0)
  )
  (junction (at 119.38 147.32) (diameter 0) (color 0 0 0 0)
  )
  (junction (at 370.84 104.14) (diameter 0) (color 0 0 0 0)
  )
  (junction (at 381 223.52) (diameter 0) (color 0 0 0 0)
  )
  (junction (at 87.63 223.52) (diameter 0) (color 0 0 0 0)
  )
  (junction (at 180.34 134.62) (diameter 0) (color 0 0 0 0)
  )
  (junction (at 364.49 234.95) (diameter 0) (color 0 0 0 0)
  )
  (junction (at 157.48 223.52) (diameter 0) (color 0 0 0 0)
  )
  (junction (at 353.06 191.77) (diameter 0) (color 0 0 0 0)
  )
  (junction (at 198.12 152.4) (diameter 0) (color 0 0 0 0)
  )
  (junction (at 364.49 223.52) (diameter 0) (color 0 0 0 0)
  )
  (junction (at 119.38 144.78) (diameter 0) (color 0 0 0 0)
  )
  (junction (at 48.26 226.06) (diameter 0) (color 0 0 0 0)
  )
  (junction (at 372.11 179.07) (diameter 0) (color 0 0 0 0)
  )
  (junction (at 373.38 48.26) (diameter 0) (color 0 0 0 0)
  )
  (junction (at 381 152.4) (diameter 0) (color 0 0 0 0)
  )
  (junction (at 381 132.08) (diameter 0) (color 0 0 0 0)
  )
  (junction (at 180.34 142.24) (diameter 0) (color 0 0 0 0)
  )
  (junction (at 365.76 36.83) (diameter 0) (color 0 0 0 0)
  )
  (junction (at 170.18 72.39) (diameter 0) (color 0 0 0 0)
  )
  (junction (at 353.06 236.22) (diameter 0) (color 0 0 0 0)
  )
  (junction (at 53.34 69.85) (diameter 0) (color 0 0 0 0)
  )
  (junction (at 238.76 124.46) (diameter 0) (color 0 0 0 0)
  )
  (junction (at 372.11 143.51) (diameter 0) (color 0 0 0 0)
  )
  (junction (at 148.59 69.85) (diameter 0) (color 0 0 0 0)
  )
  (junction (at 388.62 132.08) (diameter 0) (color 0 0 0 0)
  )
  (junction (at 397.51 36.83) (diameter 0) (color 0 0 0 0)
  )
  (junction (at 397.51 132.08) (diameter 0) (color 0 0 0 0)
  )
  (junction (at 353.06 243.84) (diameter 0) (color 0 0 0 0)
  )
  (junction (at 372.11 190.5) (diameter 0) (color 0 0 0 0)
  )
  (junction (at 44.45 38.1) (diameter 0) (color 0 0 0 0)
  )
  (junction (at 353.06 152.4) (diameter 0) (color 0 0 0 0)
  )
  (junction (at 170.18 53.34) (diameter 0) (color 0 0 0 0)
  )
  (junction (at 381 243.84) (diameter 0) (color 0 0 0 0)
  )
  (junction (at 373.38 36.83) (diameter 0) (color 0 0 0 0)
  )
  (junction (at 388.62 179.07) (diameter 0) (color 0 0 0 0)
  )
  (junction (at 381 199.39) (diameter 0) (color 0 0 0 0)
  )
  (junction (at 351.79 104.14) (diameter 0) (color 0 0 0 0)
  )
  (junction (at 238.76 201.93) (diameter 0) (color 0 0 0 0)
  )
  (junction (at 186.69 53.34) (diameter 0) (color 0 0 0 0)
  )
  (junction (at 373.38 57.15) (diameter 0) (color 0 0 0 0)
  )
  (junction (at 190.5 64.77) (diameter 0) (color 0 0 0 0)
  )
  (junction (at 363.22 95.25) (diameter 0) (color 0 0 0 0)
  )
  (junction (at 99.06 127) (diameter 0) (color 0 0 0 0)
  )
  (junction (at 238.76 86.36) (diameter 0) (color 0 0 0 0)
  )

  (no_connect (at 121.92 139.7))

  (wire (pts (xy 38.1 43.18) (xy 40.64 43.18))
    (stroke (width 0) (type default))
  )
  (wire (pts (xy 365.76 36.83) (xy 373.38 36.83))
    (stroke (width 0) (type default))
  )
  (wire (pts (xy 313.69 83.82) (xy 313.69 86.36))
    (stroke (width 0) (type default))
  )
  (wire (pts (xy 363.22 95.25) (xy 359.41 95.25))
    (stroke (width 0) (type default))
  )
  (wire (pts (xy 190.5 53.34) (xy 199.39 53.34))
    (stroke (width 0) (type default))
  )
  (wire (pts (xy 381 179.07) (xy 388.62 179.07))
    (stroke (width 0) (type default))
  )
  (wire (pts (xy 111.76 115.57) (xy 111.76 129.54))
    (stroke (width 0) (type default))
  )
  (wire (pts (xy 347.98 49.53) (xy 350.52 49.53))
    (stroke (width 0) (type default))
  )
  (wire (pts (xy 379.73 83.82) (xy 387.35 83.82))
    (stroke (width 0) (type default))
  )
  (wire (pts (xy 322.58 144.78) (xy 330.2 144.78))
    (stroke (width 0) (type default))
  )
  (wire (pts (xy 312.42 26.67) (xy 312.42 36.83))
    (stroke (width 0) (type default))
  )
  (wire (pts (xy 381 199.39) (xy 372.11 199.39))
    (stroke (width 0) (type default))
  )
  (wire (pts (xy 389.89 36.83) (xy 389.89 44.45))
    (stroke (width 0) (type default))
  )
  (wire (pts (xy 111.76 115.57) (xy 110.49 115.57))
    (stroke (width 0) (type default))
  )
  (wire (pts (xy 353.06 243.84) (xy 372.11 243.84))
    (stroke (width 0) (type default))
  )
  (wire (pts (xy 158.75 53.34) (xy 158.75 58.42))
    (stroke (width 0) (type default))
  )
  (wire (pts (xy 73.66 127) (xy 80.01 127))
    (stroke (width 0) (type default))
  )
  (wire (pts (xy 101.6 226.06) (xy 116.84 226.06))
    (stroke (width 0) (type default))
  )
  (wire (pts (xy 370.84 102.87) (xy 370.84 104.14))
    (stroke (width 0) (type default))
  )
  (wire (pts (xy 142.24 134.62) (xy 180.34 134.62))
    (stroke (width 0) (type default))
  )
  (wire (pts (xy 254 222.25) (xy 254 229.87))
    (stroke (width 0) (type default))
  )
  (wire (pts (xy 372.11 223.52) (xy 372.11 226.06))
    (stroke (width 0) (type default))
  )
  (wire (pts (xy 356.87 223.52) (xy 364.49 223.52))
    (stroke (width 0) (type default))
  )
  (wire (pts (xy 372.11 234.95) (xy 372.11 237.49))
    (stroke (width 0) (type default))
  )
  (wire (pts (xy 365.76 36.83) (xy 365.76 39.37))
    (stroke (width 0) (type default))
  )
  (wire (pts (xy 397.51 35.56) (xy 397.51 36.83))
    (stroke (width 0) (type default))
  )
  (wire (pts (xy 87.63 223.52) (xy 96.52 223.52))
    (stroke (width 0) (type default))
  )
  (wire (pts (xy 229.87 204.47) (xy 238.76 204.47))
    (stroke (width 0) (type default))
  )
  (wire (pts (xy 199.39 60.96) (xy 199.39 64.77))
    (stroke (width 0) (type default))
  )
  (wire (pts (xy 372.11 231.14) (xy 372.11 234.95))
    (stroke (width 0) (type default))
  )
  (wire (pts (xy 101.6 228.6) (xy 116.84 228.6))
    (stroke (width 0) (type default))
  )
  (wire (pts (xy 320.04 49.53) (xy 327.66 49.53))
    (stroke (width 0) (type default))
  )
  (wire (pts (xy 254 69.85) (xy 257.81 69.85))
    (stroke (width 0) (type default))
  )
  (wire (pts (xy 313.69 73.66) (xy 312.42 73.66))
    (stroke (width 0) (type default))
  )
  (wire (pts (xy 361.95 132.08) (xy 364.49 132.08))
    (stroke (width 0) (type default))
  )
  (wire (pts (xy 238.76 238.76) (xy 246.38 238.76))
    (stroke (width 0) (type default))
  )
  (wire (pts (xy 388.62 179.07) (xy 388.62 186.69))
    (stroke (width 0) (type default))
  )
  (wire (pts (xy 364.49 132.08) (xy 364.49 134.62))
    (stroke (width 0) (type default))
  )
  (wire (pts (xy 148.59 69.85) (xy 152.4 69.85))
    (stroke (width 0) (type default))
  )
  (wire (pts (xy 99.06 135.89) (xy 99.06 138.43))
    (stroke (width 0) (type default))
  )
  (wire (pts (xy 396.24 83.82) (xy 394.97 83.82))
    (stroke (width 0) (type default))
  )
  (wire (pts (xy 186.69 53.34) (xy 186.69 55.88))
    (stroke (width 0) (type default))
  )
  (wire (pts (xy 381 132.08) (xy 388.62 132.08))
    (stroke (width 0) (type default))
  )
  (wire (pts (xy 116.84 144.78) (xy 119.38 144.78))
    (stroke (width 0) (type default))
  )
  (wire (pts (xy 157.48 147.32) (xy 161.29 147.32))
    (stroke (width 0) (type default))
  )
  (wire (pts (xy 238.76 273.05) (xy 246.38 273.05))
    (stroke (width 0) (type default))
  )
  (wire (pts (xy 187.96 140.97) (xy 187.96 142.24))
    (stroke (width 0) (type default))
  )
  (wire (pts (xy 238.76 118.11) (xy 238.76 124.46))
    (stroke (width 0) (type default))
  )
  (wire (pts (xy 157.48 220.98) (xy 160.02 220.98))
    (stroke (width 0) (type default))
  )
  (wire (pts (xy 347.98 36.83) (xy 356.87 36.83))
    (stroke (width 0) (type default))
  )
  (wire (pts (xy 48.26 226.06) (xy 48.26 232.41))
    (stroke (width 0) (type default))
  )
  (wire (pts (xy 350.52 46.99) (xy 350.52 49.53))
    (stroke (width 0) (type default))
  )
  (wire (pts (xy 314.96 132.08) (xy 314.96 134.62))
    (stroke (width 0) (type default))
  )
  (wire (pts (xy 210.82 127) (xy 209.55 127))
    (stroke (width 0) (type default))
  )
  (wire (pts (xy 238.76 224.79) (xy 236.22 224.79))
    (stroke (width 0) (type default))
  )
  (wire (pts (xy 271.78 185.42) (xy 276.86 185.42))
    (stroke (width 0) (type default))
  )
  (wire (pts (xy 364.49 179.07) (xy 372.11 179.07))
    (stroke (width 0) (type default))
  )
  (wire (pts (xy 381 243.84) (xy 372.11 243.84))
    (stroke (width 0) (type default))
  )
  (wire (pts (xy 351.79 223.52) (xy 350.52 223.52))
    (stroke (width 0) (type default))
  )
  (wire (pts (xy 314.96 186.69) (xy 314.96 201.93))
    (stroke (width 0) (type default))
  )
  (wire (pts (xy 109.22 68.58) (xy 109.22 72.39))
    (stroke (width 0) (type default))
  )
  (wire (pts (xy 262.89 107.95) (xy 267.97 107.95))
    (stroke (width 0) (type default))
  )
  (wire (pts (xy 170.18 53.34) (xy 170.18 55.88))
    (stroke (width 0) (type default))
  )
  (wire (pts (xy 31.75 69.85) (xy 36.83 69.85))
    (stroke (width 0) (type default))
  )
  (wire (pts (xy 73.66 134.62) (xy 73.66 138.43))
    (stroke (width 0) (type default))
  )
  (wire (pts (xy 187.96 127) (xy 198.12 127))
    (stroke (width 0) (type default))
  )
  (wire (pts (xy 351.79 104.14) (xy 351.79 96.52))
    (stroke (width 0) (type default))
  )
  (wire (pts (xy 382.27 57.15) (xy 373.38 57.15))
    (stroke (width 0) (type default))
  )
  (wire (pts (xy 96.52 55.88) (xy 96.52 60.96))
    (stroke (width 0) (type default))
  )
  (wire (pts (xy 396.24 177.8) (xy 396.24 179.07))
    (stroke (width 0) (type default))
  )
  (wire (pts (xy 166.37 53.34) (xy 170.18 53.34))
    (stroke (width 0) (type default))
  )
  (wire (pts (xy 359.41 95.25) (xy 359.41 90.17))
    (stroke (width 0) (type default))
  )
  (wire (pts (xy 312.42 36.83) (xy 327.66 36.83))
    (stroke (width 0) (type default))
  )
  (wire (pts (xy 254 33.02) (xy 257.81 33.02))
    (stroke (width 0) (type default))
  )
  (wire (pts (xy 372.11 179.07) (xy 372.11 181.61))
    (stroke (width 0) (type default))
  )
  (wire (pts (xy 148.59 76.2) (xy 148.59 77.47))
    (stroke (width 0) (type default))
  )
  (wire (pts (xy 388.62 199.39) (xy 381 199.39))
    (stroke (width 0) (type default))
  )
  (wire (pts (xy 78.74 55.88) (xy 78.74 60.96))
    (stroke (width 0) (type default))
  )
  (wire (pts (xy 353.06 152.4) (xy 353.06 144.78))
    (stroke (width 0) (type default))
  )
  (wire (pts (xy 238.76 49.53) (xy 246.38 49.53))
    (stroke (width 0) (type default))
  )
  (wire (pts (xy 116.84 144.78) (xy 116.84 143.51))
    (stroke (width 0) (type default))
  )
  (wire (pts (xy 152.4 82.55) (xy 152.4 83.82))
    (stroke (width 0) (type default))
  )
  (wire (pts (xy 238.76 49.53) (xy 238.76 52.07))
    (stroke (width 0) (type default))
  )
  (wire (pts (xy 113.03 68.58) (xy 113.03 72.39))
    (stroke (width 0) (type default))
  )
  (wire (pts (xy 351.79 96.52) (xy 351.79 93.98))
    (stroke (width 0) (type default))
  )
  (wire (pts (xy 83.82 226.06) (xy 90.17 226.06))
    (stroke (width 0) (type default))
  )
  (wire (pts (xy 388.62 144.78) (xy 388.62 152.4))
    (stroke (width 0) (type default))
  )
  (wire (pts (xy 186.69 64.77) (xy 186.69 67.31))
    (stroke (width 0) (type default))
  )
  (wire (pts (xy 365.76 48.26) (xy 356.87 48.26))
    (stroke (width 0) (type default))
  )
  (wire (pts (xy 176.53 142.24) (xy 180.34 142.24))
    (stroke (width 0) (type default))
  )
  (wire (pts (xy 353.06 152.4) (xy 372.11 152.4))
    (stroke (width 0) (type default))
  )
  (wire (pts (xy 364.49 179.07) (xy 364.49 181.61))
    (stroke (width 0) (type default))
  )
  (wire (pts (xy 398.78 36.83) (xy 397.51 36.83))
    (stroke (width 0) (type default))
  )
  (wire (pts (xy 238.76 110.49) (xy 236.22 110.49))
    (stroke (width 0) (type default))
  )
  (wire (pts (xy 353.06 158.75) (xy 353.06 152.4))
    (stroke (width 0) (type default))
  )
  (wire (pts (xy 373.38 36.83) (xy 373.38 39.37))
    (stroke (width 0) (type default))
  )
  (wire (pts (xy 381 223.52) (xy 388.62 223.52))
    (stroke (width 0) (type default))
  )
  (wire (pts (xy 254 92.71) (xy 254 90.17))
    (stroke (width 0) (type default))
  )
  (wire (pts (xy 397.51 222.25) (xy 397.51 223.52))
    (stroke (width 0) (type default))
  )
  (wire (pts (xy 347.98 43.18) (xy 356.87 43.18))
    (stroke (width 0) (type default))
  )
  (wire (pts (xy 372.11 190.5) (xy 372.11 191.77))
    (stroke (width 0) (type default))
  )
  (wire (pts (xy 365.76 44.45) (xy 365.76 48.26))
    (stroke (width 0) (type default))
  )
  (wire (pts (xy 389.89 179.07) (xy 388.62 179.07))
    (stroke (width 0) (type default))
  )
  (wire (pts (xy 254 168.91) (xy 254 166.37))
    (stroke (width 0) (type default))
  )
  (wire (pts (xy 119.38 152.4) (xy 119.38 149.86))
    (stroke (width 0) (type default))
  )
  (wire (pts (xy 254 107.95) (xy 257.81 107.95))
    (stroke (width 0) (type default))
  )
  (wire (pts (xy 372.11 186.69) (xy 372.11 190.5))
    (stroke (width 0) (type default))
  )
  (wire (pts (xy 372.11 139.7) (xy 372.11 143.51))
    (stroke (width 0) (type default))
  )
  (wire (pts (xy 321.31 96.52) (xy 328.93 96.52))
    (stroke (width 0) (type default))
  )
  (wire (pts (xy 238.76 72.39) (xy 236.22 72.39))
    (stroke (width 0) (type default))
  )
  (wire (pts (xy 330.2 185.42) (xy 320.04 185.42))
    (stroke (width 0) (type default))
  )
  (wire (pts (xy 350.52 144.78) (xy 353.06 144.78))
    (stroke (width 0) (type default))
  )
  (wire (pts (xy 364.49 186.69) (xy 364.49 190.5))
    (stroke (width 0) (type default))
  )
  (wire (pts (xy 186.69 53.34) (xy 190.5 53.34))
    (stroke (width 0) (type default))
  )
  (wire (pts (xy 36.83 69.85) (xy 43.18 69.85))
    (stroke (width 0) (type default))
  )
  (wire (pts (xy 350.52 83.82) (xy 349.25 83.82))
    (stroke (width 0) (type default))
  )
  (wire (pts (xy 353.06 233.68) (xy 350.52 233.68))
    (stroke (width 0) (type default))
  )
  (wire (pts (xy 363.22 91.44) (xy 363.22 95.25))
    (stroke (width 0) (type default))
  )
  (wire (pts (xy 351.79 93.98) (xy 349.25 93.98))
    (stroke (width 0) (type default))
  )
  (wire (pts (xy 356.87 179.07) (xy 364.49 179.07))
    (stroke (width 0) (type default))
  )
  (wire (pts (xy 209.55 127) (xy 208.28 127))
    (stroke (width 0) (type default))
  )
  (wire (pts (xy 180.34 134.62) (xy 180.34 142.24))
    (stroke (width 0) (type default))
  )
  (wire (pts (xy 353.06 189.23) (xy 350.52 189.23))
    (stroke (width 0) (type default))
  )
  (wire (pts (xy 157.48 137.16) (xy 157.48 142.24))
    (stroke (width 0) (type default))
  )
  (wire (pts (xy 48.26 208.28) (xy 48.26 212.09))
    (stroke (width 0) (type default))
  )
  (wire (pts (xy 144.78 69.85) (xy 148.59 69.85))
    (stroke (width 0) (type default))
  )
  (wire (pts (xy 63.5 237.49) (xy 63.5 238.76))
    (stroke (width 0) (type default))
  )
  (wire (pts (xy 359.41 90.17) (xy 349.25 90.17))
    (stroke (width 0) (type default))
  )
  (wire (pts (xy 262.89 256.54) (xy 267.97 256.54))
    (stroke (width 0) (type default))
  )
  (wire (pts (xy 187.96 149.86) (xy 187.96 152.4))
    (stroke (width 0) (type default))
  )
  (wire (pts (xy 92.71 218.44) (xy 92.71 228.6))
    (stroke (width 0) (type default))
  )
  (wire (pts (xy 273.05 222.25) (xy 276.86 222.25))
    (stroke (width 0) (type default))
  )
  (wire (pts (xy 254 222.25) (xy 257.81 222.25))
    (stroke (width 0) (type default))
  )
  (wire (pts (xy 187.96 127) (xy 180.34 127))
    (stroke (width 0) (type default))
  )
  (wire (pts (xy 353.06 247.65) (xy 353.06 243.84))
    (stroke (width 0) (type default))
  )
  (wire (pts (xy 229.87 241.3) (xy 238.76 241.3))
    (stroke (width 0) (type default))
  )
  (wire (pts (xy 262.89 69.85) (xy 267.97 69.85))
    (stroke (width 0) (type default))
  )
  (wire (pts (xy 48.26 226.06) (xy 67.31 226.06))
    (stroke (width 0) (type default))
  )
  (wire (pts (xy 109.22 58.42) (xy 109.22 63.5))
    (stroke (width 0) (type default))
  )
  (wire (pts (xy 238.76 201.93) (xy 246.38 201.93))
    (stroke (width 0) (type default))
  )
  (wire (pts (xy 170.18 60.96) (xy 170.18 63.5))
    (stroke (width 0) (type default))
  )
  (wire (pts (xy 372.11 223.52) (xy 381 223.52))
    (stroke (width 0) (type default))
  )
  (wire (pts (xy 198.12 152.4) (xy 198.12 153.67))
    (stroke (width 0) (type default))
  )
  (wire (pts (xy 119.38 149.86) (xy 121.92 149.86))
    (stroke (width 0) (type default))
  )
  (wire (pts (xy 154.94 127) (xy 180.34 127))
    (stroke (width 0) (type default))
  )
  (wire (pts (xy 116.84 137.16) (xy 116.84 138.43))
    (stroke (width 0) (type default))
  )
  (wire (pts (xy 381 152.4) (xy 372.11 152.4))
    (stroke (width 0) (type default))
  )
  (wire (pts (xy 327.66 43.18) (xy 316.23 43.18))
    (stroke (width 0) (type default))
  )
  (wire (pts (xy 262.89 33.02) (xy 267.97 33.02))
    (stroke (width 0) (type default))
  )
  (wire (pts (xy 273.05 146.05) (xy 276.86 146.05))
    (stroke (width 0) (type default))
  )
  (wire (pts (xy 262.89 185.42) (xy 266.7 185.42))
    (stroke (width 0) (type default))
  )
  (wire (pts (xy 314.96 121.92) (xy 314.96 132.08))
    (stroke (width 0) (type default))
  )
  (wire (pts (xy 388.62 223.52) (xy 388.62 231.14))
    (stroke (width 0) (type default))
  )
  (wire (pts (xy 238.76 224.79) (xy 238.76 228.6))
    (stroke (width 0) (type default))
  )
  (wire (pts (xy 153.67 53.34) (xy 158.75 53.34))
    (stroke (width 0) (type default))
  )
  (wire (pts (xy 92.71 209.55) (xy 92.71 213.36))
    (stroke (width 0) (type default))
  )
  (wire (pts (xy 254 146.05) (xy 257.81 146.05))
    (stroke (width 0) (type default))
  )
  (wire (pts (xy 115.57 50.8) (xy 115.57 40.64))
    (stroke (width 0) (type default))
  )
  (wire (pts (xy 350.52 57.15) (xy 350.52 58.42))
    (stroke (width 0) (type default))
  )
  (wire (pts (xy 364.49 139.7) (xy 364.49 143.51))
    (stroke (width 0) (type default))
  )
  (wire (pts (xy 48.26 237.49) (xy 48.26 238.76))
    (stroke (width 0) (type default))
  )
  (wire (pts (xy 186.69 60.96) (xy 186.69 64.77))
    (stroke (width 0) (type default))
  )
  (wire (pts (xy 273.05 33.02) (xy 276.86 33.02))
    (stroke (width 0) (type default))
  )
  (wire (pts (xy 262.89 222.25) (xy 267.97 222.25))
    (stroke (width 0) (type default))
  )
  (wire (pts (xy 370.84 95.25) (xy 370.84 97.79))
    (stroke (width 0) (type default))
  )
  (wire (pts (xy 158.75 58.42) (xy 158.75 59.69))
    (stroke (width 0) (type default))
  )
  (wire (pts (xy 238.76 187.96) (xy 238.76 190.5))
    (stroke (width 0) (type default))
  )
  (wire (pts (xy 187.96 152.4) (xy 198.12 152.4))
    (stroke (width 0) (type default))
  )
  (wire (pts (xy 314.96 139.7) (xy 314.96 157.48))
    (stroke (width 0) (type default))
  )
  (wire (pts (xy 90.17 226.06) (xy 96.52 226.06))
    (stroke (width 0) (type default))
  )
  (wire (pts (xy 80.01 138.43) (xy 73.66 138.43))
    (stroke (width 0) (type default))
  )
  (wire (pts (xy 238.76 195.58) (xy 238.76 201.93))
    (stroke (width 0) (type default))
  )
  (wire (pts (xy 90.17 209.55) (xy 92.71 209.55))
    (stroke (width 0) (type default))
  )
  (wire (pts (xy 209.55 52.07) (xy 209.55 53.34))
    (stroke (width 0) (type default))
  )
  (wire (pts (xy 119.38 149.86) (xy 119.38 147.32))
    (stroke (width 0) (type default))
  )
  (wire (pts (xy 350.52 191.77) (xy 353.06 191.77))
    (stroke (width 0) (type default))
  )
  (wire (pts (xy 238.76 273.05) (xy 238.76 275.59))
    (stroke (width 0) (type default))
  )
  (wire (pts (xy 152.4 83.82) (xy 152.4 85.09))
    (stroke (width 0) (type default))
  )
  (wire (pts (xy 78.74 66.04) (xy 78.74 72.39))
    (stroke (width 0) (type default))
  )
  (wire (pts (xy 157.48 223.52) (xy 160.02 223.52))
    (stroke (width 0) (type default))
  )
  (wire (pts (xy 157.48 223.52) (xy 157.48 226.06))
    (stroke (width 0) (type default))
  )
  (wire (pts (xy 142.24 127) (xy 149.86 127))
    (stroke (width 0) (type default))
  )
  (wire (pts (xy 364.49 190.5) (xy 360.68 190.5))
    (stroke (width 0) (type default))
  )
  (wire (pts (xy 364.49 234.95) (xy 360.68 234.95))
    (stroke (width 0) (type default))
  )
  (wire (pts (xy 148.59 82.55) (xy 148.59 83.82))
    (stroke (width 0) (type default))
  )
  (wire (pts (xy 353.06 144.78) (xy 353.06 142.24))
    (stroke (width 0) (type default))
  )
  (wire (pts (xy 198.12 123.19) (xy 198.12 127))
    (stroke (width 0) (type default))
  )
  (wire (pts (xy 314.96 223.52) (xy 330.2 223.52))
    (stroke (width 0) (type default))
  )
  (wire (pts (xy 40.64 40.64) (xy 40.64 43.18))
    (stroke (width 0) (type default))
  )
  (wire (pts (xy 397.51 83.82) (xy 396.24 83.82))
    (stroke (width 0) (type default))
  )
  (wire (pts (xy 144.78 53.34) (xy 148.59 53.34))
    (stroke (width 0) (type default))
  )
  (wire (pts (xy 381 236.22) (xy 381 243.84))
    (stroke (width 0) (type default))
  )
  (wire (pts (xy 40.64 43.18) (xy 40.64 50.8))
    (stroke (width 0) (type default))
  )
  (wire (pts (xy 157.48 142.24) (xy 157.48 147.32))
    (stroke (width 0) (type default))
  )
  (wire (pts (xy 313.69 73.66) (xy 313.69 83.82))
    (stroke (width 0) (type default))
  )
  (wire (pts (xy 382.27 49.53) (xy 382.27 57.15))
    (stroke (width 0) (type default))
  )
  (wire (pts (xy 396.24 82.55) (xy 396.24 83.82))
    (stroke (width 0) (type default))
  )
  (wire (pts (xy 170.18 72.39) (xy 170.18 68.58))
    (stroke (width 0) (type default))
  )
  (wire (pts (xy 152.4 83.82) (xy 148.59 83.82))
    (stroke (width 0) (type default))
  )
  (wire (pts (xy 254 185.42) (xy 257.81 185.42))
    (stroke (width 0) (type default))
  )
  (wire (pts (xy 360.68 143.51) (xy 360.68 138.43))
    (stroke (width 0) (type default))
  )
  (wire (pts (xy 142.24 137.16) (xy 157.48 137.16))
    (stroke (width 0) (type default))
  )
  (wire (pts (xy 387.35 83.82) (xy 389.89 83.82))
    (stroke (width 0) (type default))
  )
  (wire (pts (xy 312.42 36.83) (xy 312.42 39.37))
    (stroke (width 0) (type default))
  )
  (wire (pts (xy 314.96 179.07) (xy 314.96 181.61))
    (stroke (width 0) (type default))
  )
  (wire (pts (xy 85.09 231.14) (xy 83.82 231.14))
    (stroke (width 0) (type default))
  )
  (wire (pts (xy 116.84 69.85) (xy 116.84 72.39))
    (stroke (width 0) (type default))
  )
  (wire (pts (xy 372.11 190.5) (xy 364.49 190.5))
    (stroke (width 0) (type default))
  )
  (wire (pts (xy 387.35 104.14) (xy 379.73 104.14))
    (stroke (width 0) (type default))
  )
  (wire (pts (xy 353.06 236.22) (xy 353.06 233.68))
    (stroke (width 0) (type default))
  )
  (wire (pts (xy 314.96 232.41) (xy 314.96 246.38))
    (stroke (width 0) (type default))
  )
  (wire (pts (xy 388.62 222.25) (xy 388.62 223.52))
    (stroke (width 0) (type default))
  )
  (wire (pts (xy 391.16 132.08) (xy 388.62 132.08))
    (stroke (width 0) (type default))
  )
  (wire (pts (xy 166.37 142.24) (xy 171.45 142.24))
    (stroke (width 0) (type default))
  )
  (wire (pts (xy 119.38 60.96) (xy 113.03 60.96))
    (stroke (width 0) (type default))
  )
  (wire (pts (xy 314.96 179.07) (xy 330.2 179.07))
    (stroke (width 0) (type default))
  )
  (wire (pts (xy 360.68 185.42) (xy 350.52 185.42))
    (stroke (width 0) (type default))
  )
  (wire (pts (xy 238.76 72.39) (xy 238.76 74.93))
    (stroke (width 0) (type default))
  )
  (wire (pts (xy 90.17 208.28) (xy 90.17 209.55))
    (stroke (width 0) (type default))
  )
  (wire (pts (xy 201.93 53.34) (xy 199.39 53.34))
    (stroke (width 0) (type default))
  )
  (wire (pts (xy 328.93 90.17) (xy 318.77 90.17))
    (stroke (width 0) (type default))
  )
  (wire (pts (xy 87.63 66.04) (xy 87.63 72.39))
    (stroke (width 0) (type default))
  )
  (wire (pts (xy 397.51 223.52) (xy 396.24 223.52))
    (stroke (width 0) (type default))
  )
  (wire (pts (xy 90.17 209.55) (xy 90.17 213.36))
    (stroke (width 0) (type default))
  )
  (wire (pts (xy 231.14 52.07) (xy 238.76 52.07))
    (stroke (width 0) (type default))
  )
  (wire (pts (xy 314.96 213.36) (xy 314.96 223.52))
    (stroke (width 0) (type default))
  )
  (wire (pts (xy 397.51 132.08) (xy 396.24 132.08))
    (stroke (width 0) (type default))
  )
  (wire (pts (xy 170.18 82.55) (xy 170.18 85.09))
    (stroke (width 0) (type default))
  )
  (wire (pts (xy 349.25 96.52) (xy 351.79 96.52))
    (stroke (width 0) (type default))
  )
  (wire (pts (xy 229.87 275.59) (xy 238.76 275.59))
    (stroke (width 0) (type default))
  )
  (wire (pts (xy 373.38 54.61) (xy 373.38 57.15))
    (stroke (width 0) (type default))
  )
  (wire (pts (xy 370.84 83.82) (xy 379.73 83.82))
    (stroke (width 0) (type default))
  )
  (wire (pts (xy 238.76 35.56) (xy 238.76 39.37))
    (stroke (width 0) (type default))
  )
  (wire (pts (xy 119.38 69.85) (xy 116.84 69.85))
    (stroke (width 0) (type default))
  )
  (wire (pts (xy 187.96 142.24) (xy 187.96 144.78))
    (stroke (width 0) (type default))
  )
  (wire (pts (xy 95.25 127) (xy 99.06 127))
    (stroke (width 0) (type default))
  )
  (wire (pts (xy 387.35 96.52) (xy 387.35 104.14))
    (stroke (width 0) (type default))
  )
  (wire (pts (xy 238.76 86.36) (xy 238.76 88.9))
    (stroke (width 0) (type default))
  )
  (wire (pts (xy 398.78 132.08) (xy 397.51 132.08))
    (stroke (width 0) (type default))
  )
  (wire (pts (xy 389.89 49.53) (xy 389.89 57.15))
    (stroke (width 0) (type default))
  )
  (wire (pts (xy 63.5 231.14) (xy 63.5 232.41))
    (stroke (width 0) (type default))
  )
  (wire (pts (xy 180.34 142.24) (xy 180.34 147.32))
    (stroke (width 0) (type default))
  )
  (wire (pts (xy 372.11 234.95) (xy 364.49 234.95))
    (stroke (width 0) (type default))
  )
  (wire (pts (xy 238.76 86.36) (xy 246.38 86.36))
    (stroke (width 0) (type default))
  )
  (wire (pts (xy 38.1 40.64) (xy 40.64 40.64))
    (stroke (width 0) (type default))
  )
  (wire (pts (xy 99.06 138.43) (xy 80.01 138.43))
    (stroke (width 0) (type default))
  )
  (wire (pts (xy 180.34 142.24) (xy 187.96 142.24))
    (stroke (width 0) (type default))
  )
  (wire (pts (xy 273.05 69.85) (xy 276.86 69.85))
    (stroke (width 0) (type default))
  )
  (wire (pts (xy 238.76 124.46) (xy 238.76 127))
    (stroke (width 0) (type default))
  )
  (wire (pts (xy 238.76 259.08) (xy 236.22 259.08))
    (stroke (width 0) (type default))
  )
  (wire (pts (xy 254 256.54) (xy 254 264.16))
    (stroke (width 0) (type default))
  )
  (wire (pts (xy 314.96 132.08) (xy 330.2 132.08))
    (stroke (width 0) (type default))
  )
  (wire (pts (xy 330.2 138.43) (xy 320.04 138.43))
    (stroke (width 0) (type default))
  )
  (wire (pts (xy 87.63 209.55) (xy 87.63 213.36))
    (stroke (width 0) (type default))
  )
  (wire (pts (xy 379.73 83.82) (xy 379.73 91.44))
    (stroke (width 0) (type default))
  )
  (wire (pts (xy 80.01 127) (xy 80.01 129.54))
    (stroke (width 0) (type default))
  )
  (wire (pts (xy 360.68 190.5) (xy 360.68 185.42))
    (stroke (width 0) (type default))
  )
  (wire (pts (xy 391.16 36.83) (xy 389.89 36.83))
    (stroke (width 0) (type default))
  )
  (wire (pts (xy 387.35 82.55) (xy 387.35 83.82))
    (stroke (width 0) (type default))
  )
  (wire (pts (xy 90.17 218.44) (xy 90.17 226.06))
    (stroke (width 0) (type default))
  )
  (wire (pts (xy 254 146.05) (xy 254 153.67))
    (stroke (width 0) (type default))
  )
  (wire (pts (xy 360.68 138.43) (xy 350.52 138.43))
    (stroke (width 0) (type default))
  )
  (wire (pts (xy 370.84 95.25) (xy 363.22 95.25))
    (stroke (width 0) (type default))
  )
  (wire (pts (xy 330.2 229.87) (xy 320.04 229.87))
    (stroke (width 0) (type default))
  )
  (wire (pts (xy 85.09 238.76) (xy 85.09 231.14))
    (stroke (width 0) (type default))
  )
  (wire (pts (xy 48.26 49.53) (xy 48.26 50.8))
    (stroke (width 0) (type default))
  )
  (wire (pts (xy 350.52 132.08) (xy 356.87 132.08))
    (stroke (width 0) (type default))
  )
  (wire (pts (xy 53.34 68.58) (xy 53.34 69.85))
    (stroke (width 0) (type default))
  )
  (wire (pts (xy 87.63 218.44) (xy 87.63 223.52))
    (stroke (width 0) (type default))
  )
  (wire (pts (xy 154.94 72.39) (xy 170.18 72.39))
    (stroke (width 0) (type default))
  )
  (wire (pts (xy 381 132.08) (xy 381 139.7))
    (stroke (width 0) (type default))
  )
  (wire (pts (xy 350.52 49.53) (xy 350.52 57.15))
    (stroke (width 0) (type default))
  )
  (wire (pts (xy 381 179.07) (xy 381 186.69))
    (stroke (width 0) (type default))
  )
  (wire (pts (xy 158.75 53.34) (xy 161.29 53.34))
    (stroke (width 0) (type default))
  )
  (wire (pts (xy 198.12 140.97) (xy 198.12 152.4))
    (stroke (width 0) (type default))
  )
  (wire (pts (xy 388.62 177.8) (xy 388.62 179.07))
    (stroke (width 0) (type default))
  )
  (wire (pts (xy 262.89 146.05) (xy 267.97 146.05))
    (stroke (width 0) (type default))
  )
  (wire (pts (xy 313.69 83.82) (xy 328.93 83.82))
    (stroke (width 0) (type default))
  )
  (wire (pts (xy 360.68 234.95) (xy 360.68 229.87))
    (stroke (width 0) (type default))
  )
  (wire (pts (xy 96.52 66.04) (xy 96.52 72.39))
    (stroke (width 0) (type default))
  )
  (wire (pts (xy 111.76 129.54) (xy 121.92 129.54))
    (stroke (width 0) (type default))
  )
  (wire (pts (xy 351.79 105.41) (xy 351.79 104.14))
    (stroke (width 0) (type default))
  )
  (wire (pts (xy 389.89 57.15) (xy 382.27 57.15))
    (stroke (width 0) (type default))
  )
  (wire (pts (xy 351.79 104.14) (xy 370.84 104.14))
    (stroke (width 0) (type default))
  )
  (wire (pts (xy 238.76 110.49) (xy 238.76 113.03))
    (stroke (width 0) (type default))
  )
  (wire (pts (xy 388.62 236.22) (xy 388.62 243.84))
    (stroke (width 0) (type default))
  )
  (wire (pts (xy 99.06 127) (xy 121.92 127))
    (stroke (width 0) (type default))
  )
  (wire (pts (xy 142.24 139.7) (xy 149.86 139.7))
    (stroke (width 0) (type default))
  )
  (wire (pts (xy 99.06 127) (xy 99.06 130.81))
    (stroke (width 0) (type default))
  )
  (wire (pts (xy 370.84 83.82) (xy 370.84 87.63))
    (stroke (width 0) (type default))
  )
  (wire (pts (xy 157.48 220.98) (xy 157.48 223.52))
    (stroke (width 0) (type default))
  )
  (wire (pts (xy 34.29 226.06) (xy 48.26 226.06))
    (stroke (width 0) (type default))
  )
  (wire (pts (xy 373.38 48.26) (xy 365.76 48.26))
    (stroke (width 0) (type default))
  )
  (wire (pts (xy 353.06 203.2) (xy 353.06 199.39))
    (stroke (width 0) (type default))
  )
  (wire (pts (xy 254 55.88) (xy 254 53.34))
    (stroke (width 0) (type default))
  )
  (wire (pts (xy 238.76 259.08) (xy 238.76 261.62))
    (stroke (width 0) (type default))
  )
  (wire (pts (xy 370.84 92.71) (xy 370.84 95.25))
    (stroke (width 0) (type default))
  )
  (wire (pts (xy 254 256.54) (xy 257.81 256.54))
    (stroke (width 0) (type default))
  )
  (wire (pts (xy 38.1 38.1) (xy 44.45 38.1))
    (stroke (width 0) (type default))
  )
  (wire (pts (xy 361.95 36.83) (xy 365.76 36.83))
    (stroke (width 0) (type default))
  )
  (wire (pts (xy 238.76 187.96) (xy 237.49 187.96))
    (stroke (width 0) (type default))
  )
  (wire (pts (xy 372.11 179.07) (xy 381 179.07))
    (stroke (width 0) (type default))
  )
  (wire (pts (xy 396.24 179.07) (xy 394.97 179.07))
    (stroke (width 0) (type default))
  )
  (wire (pts (xy 373.38 36.83) (xy 382.27 36.83))
    (stroke (width 0) (type default))
  )
  (wire (pts (xy 372.11 151.13) (xy 372.11 152.4))
    (stroke (width 0) (type default))
  )
  (wire (pts (xy 254 279.4) (xy 254 276.86))
    (stroke (width 0) (type default))
  )
  (wire (pts (xy 148.59 69.85) (xy 148.59 71.12))
    (stroke (width 0) (type default))
  )
  (wire (pts (xy 254 208.28) (xy 254 205.74))
    (stroke (width 0) (type default))
  )
  (wire (pts (xy 119.38 58.42) (xy 109.22 58.42))
    (stroke (width 0) (type default))
  )
  (wire (pts (xy 170.18 53.34) (xy 186.69 53.34))
    (stroke (width 0) (type default))
  )
  (wire (pts (xy 314.96 223.52) (xy 314.96 227.33))
    (stroke (width 0) (type default))
  )
  (wire (pts (xy 73.66 127) (xy 73.66 129.54))
    (stroke (width 0) (type default))
  )
  (wire (pts (xy 86.36 118.11) (xy 86.36 127))
    (stroke (width 0) (type default))
  )
  (wire (pts (xy 372.11 196.85) (xy 372.11 199.39))
    (stroke (width 0) (type default))
  )
  (wire (pts (xy 364.49 223.52) (xy 364.49 226.06))
    (stroke (width 0) (type default))
  )
  (wire (pts (xy 86.36 127) (xy 90.17 127))
    (stroke (width 0) (type default))
  )
  (wire (pts (xy 199.39 53.34) (xy 199.39 55.88))
    (stroke (width 0) (type default))
  )
  (wire (pts (xy 254 69.85) (xy 254 77.47))
    (stroke (width 0) (type default))
  )
  (wire (pts (xy 119.38 50.8) (xy 115.57 50.8))
    (stroke (width 0) (type default))
  )
  (wire (pts (xy 388.62 243.84) (xy 381 243.84))
    (stroke (width 0) (type default))
  )
  (wire (pts (xy 236.22 127) (xy 238.76 127))
    (stroke (width 0) (type default))
  )
  (wire (pts (xy 353.06 199.39) (xy 372.11 199.39))
    (stroke (width 0) (type default))
  )
  (wire (pts (xy 238.76 44.45) (xy 238.76 49.53))
    (stroke (width 0) (type default))
  )
  (wire (pts (xy 67.31 223.52) (xy 62.23 223.52))
    (stroke (width 0) (type default))
  )
  (wire (pts (xy 351.79 179.07) (xy 350.52 179.07))
    (stroke (width 0) (type default))
  )
  (wire (pts (xy 387.35 83.82) (xy 387.35 91.44))
    (stroke (width 0) (type default))
  )
  (wire (pts (xy 86.36 118.11) (xy 81.28 118.11))
    (stroke (width 0) (type default))
  )
  (wire (pts (xy 55.88 228.6) (xy 55.88 238.76))
    (stroke (width 0) (type default))
  )
  (wire (pts (xy 238.76 238.76) (xy 238.76 241.3))
    (stroke (width 0) (type default))
  )
  (wire (pts (xy 382.27 36.83) (xy 382.27 44.45))
    (stroke (width 0) (type default))
  )
  (wire (pts (xy 363.22 83.82) (xy 363.22 86.36))
    (stroke (width 0) (type default))
  )
  (wire (pts (xy 166.37 147.32) (xy 180.34 147.32))
    (stroke (width 0) (type default))
  )
  (wire (pts (xy 382.27 36.83) (xy 389.89 36.83))
    (stroke (width 0) (type default))
  )
  (wire (pts (xy 238.76 124.46) (xy 246.38 124.46))
    (stroke (width 0) (type default))
  )
  (wire (pts (xy 119.38 147.32) (xy 119.38 144.78))
    (stroke (width 0) (type default))
  )
  (wire (pts (xy 80.01 134.62) (xy 80.01 138.43))
    (stroke (width 0) (type default))
  )
  (wire (pts (xy 353.06 243.84) (xy 353.06 236.22))
    (stroke (width 0) (type default))
  )
  (wire (pts (xy 121.92 134.62) (xy 110.49 134.62))
    (stroke (width 0) (type default))
  )
  (wire (pts (xy 209.55 125.73) (xy 209.55 127))
    (stroke (width 0) (type default))
  )
  (wire (pts (xy 322.58 236.22) (xy 330.2 236.22))
    (stroke (width 0) (type default))
  )
  (wire (pts (xy 372.11 143.51) (xy 364.49 143.51))
    (stroke (width 0) (type default))
  )
  (wire (pts (xy 373.38 48.26) (xy 373.38 49.53))
    (stroke (width 0) (type default))
  )
  (wire (pts (xy 372.11 143.51) (xy 372.11 146.05))
    (stroke (width 0) (type default))
  )
  (wire (pts (xy 180.34 133.35) (xy 180.34 134.62))
    (stroke (width 0) (type default))
  )
  (wire (pts (xy 187.96 134.62) (xy 187.96 135.89))
    (stroke (width 0) (type default))
  )
  (wire (pts (xy 170.18 72.39) (xy 170.18 77.47))
    (stroke (width 0) (type default))
  )
  (wire (pts (xy 364.49 143.51) (xy 360.68 143.51))
    (stroke (width 0) (type default))
  )
  (wire (pts (xy 87.63 209.55) (xy 90.17 209.55))
    (stroke (width 0) (type default))
  )
  (wire (pts (xy 312.42 44.45) (xy 312.42 58.42))
    (stroke (width 0) (type default))
  )
  (wire (pts (xy 157.48 142.24) (xy 161.29 142.24))
    (stroke (width 0) (type default))
  )
  (wire (pts (xy 207.01 53.34) (xy 209.55 53.34))
    (stroke (width 0) (type default))
  )
  (wire (pts (xy 36.83 68.58) (xy 36.83 69.85))
    (stroke (width 0) (type default))
  )
  (wire (pts (xy 62.23 208.28) (xy 62.23 223.52))
    (stroke (width 0) (type default))
  )
  (wire (pts (xy 154.94 64.77) (xy 154.94 72.39))
    (stroke (width 0) (type default))
  )
  (wire (pts (xy 350.52 236.22) (xy 353.06 236.22))
    (stroke (width 0) (type default))
  )
  (wire (pts (xy 398.78 223.52) (xy 397.51 223.52))
    (stroke (width 0) (type default))
  )
  (wire (pts (xy 53.34 69.85) (xy 57.15 69.85))
    (stroke (width 0) (type default))
  )
  (wire (pts (xy 63.5 231.14) (xy 67.31 231.14))
    (stroke (width 0) (type default))
  )
  (wire (pts (xy 190.5 60.96) (xy 190.5 64.77))
    (stroke (width 0) (type default))
  )
  (wire (pts (xy 273.05 256.54) (xy 276.86 256.54))
    (stroke (width 0) (type default))
  )
  (wire (pts (xy 397.51 36.83) (xy 396.24 36.83))
    (stroke (width 0) (type default))
  )
  (wire (pts (xy 238.76 201.93) (xy 238.76 204.47))
    (stroke (width 0) (type default))
  )
  (wire (pts (xy 92.71 228.6) (xy 96.52 228.6))
    (stroke (width 0) (type default))
  )
  (wire (pts (xy 73.66 139.7) (xy 73.66 138.43))
    (stroke (width 0) (type default))
  )
  (wire (pts (xy 273.05 107.95) (xy 276.86 107.95))
    (stroke (width 0) (type default))
  )
  (wire (pts (xy 373.38 44.45) (xy 373.38 48.26))
    (stroke (width 0) (type default))
  )
  (wire (pts (xy 55.88 228.6) (xy 67.31 228.6))
    (stroke (width 0) (type default))
  )
  (wire (pts (xy 229.87 162.56) (xy 246.38 162.56))
    (stroke (width 0) (type default))
  )
  (wire (pts (xy 355.6 83.82) (xy 363.22 83.82))
    (stroke (width 0) (type default))
  )
  (wire (pts (xy 113.03 60.96) (xy 113.03 63.5))
    (stroke (width 0) (type default))
  )
  (wire (pts (xy 370.84 104.14) (xy 379.73 104.14))
    (stroke (width 0) (type default))
  )
  (wire (pts (xy 203.2 127) (xy 198.12 127))
    (stroke (width 0) (type default))
  )
  (wire (pts (xy 228.6 88.9) (xy 238.76 88.9))
    (stroke (width 0) (type default))
  )
  (wire (pts (xy 238.76 80.01) (xy 238.76 86.36))
    (stroke (width 0) (type default))
  )
  (wire (pts (xy 381 223.52) (xy 381 231.14))
    (stroke (width 0) (type default))
  )
  (wire (pts (xy 322.58 191.77) (xy 330.2 191.77))
    (stroke (width 0) (type default))
  )
  (wire (pts (xy 83.82 223.52) (xy 87.63 223.52))
    (stroke (width 0) (type default))
  )
  (wire (pts (xy 144.78 58.42) (xy 158.75 58.42))
    (stroke (width 0) (type default))
  )
  (wire (pts (xy 152.4 69.85) (xy 152.4 77.47))
    (stroke (width 0) (type default))
  )
  (wire (pts (xy 186.69 64.77) (xy 190.5 64.77))
    (stroke (width 0) (type default))
  )
  (wire (pts (xy 209.55 53.34) (xy 212.09 53.34))
    (stroke (width 0) (type default))
  )
  (wire (pts (xy 238.76 35.56) (xy 237.49 35.56))
    (stroke (width 0) (type default))
  )
  (wire (pts (xy 48.26 69.85) (xy 53.34 69.85))
    (stroke (width 0) (type default))
  )
  (wire (pts (xy 190.5 53.34) (xy 190.5 55.88))
    (stroke (width 0) (type default))
  )
  (wire (pts (xy 144.78 50.8) (xy 152.4 50.8))
    (stroke (width 0) (type default))
  )
  (wire (pts (xy 381 144.78) (xy 381 152.4))
    (stroke (width 0) (type default))
  )
  (wire (pts (xy 48.26 217.17) (xy 48.26 226.06))
    (stroke (width 0) (type default))
  )
  (wire (pts (xy 154.94 218.44) (xy 160.02 218.44))
    (stroke (width 0) (type default))
  )
  (wire (pts (xy 350.52 57.15) (xy 373.38 57.15))
    (stroke (width 0) (type default))
  )
  (wire (pts (xy 313.69 91.44) (xy 313.69 105.41))
    (stroke (width 0) (type default))
  )
  (wire (pts (xy 381 191.77) (xy 381 199.39))
    (stroke (width 0) (type default))
  )
  (wire (pts (xy 119.38 53.34) (xy 115.57 53.34))
    (stroke (width 0) (type default))
  )
  (wire (pts (xy 187.96 127) (xy 187.96 129.54))
    (stroke (width 0) (type default))
  )
  (wire (pts (xy 363.22 83.82) (xy 370.84 83.82))
    (stroke (width 0) (type default))
  )
  (wire (pts (xy 379.73 96.52) (xy 379.73 104.14))
    (stroke (width 0) (type default))
  )
  (wire (pts (xy 144.78 64.77) (xy 154.94 64.77))
    (stroke (width 0) (type default))
  )
  (wire (pts (xy 353.06 142.24) (xy 350.52 142.24))
    (stroke (width 0) (type default))
  )
  (wire (pts (xy 238.76 266.7) (xy 238.76 273.05))
    (stroke (width 0) (type default))
  )
  (wire (pts (xy 372.11 132.08) (xy 372.11 134.62))
    (stroke (width 0) (type default))
  )
  (wire (pts (xy 388.62 130.81) (xy 388.62 132.08))
    (stroke (width 0) (type default))
  )
  (wire (pts (xy 238.76 233.68) (xy 238.76 238.76))
    (stroke (width 0) (type default))
  )
  (wire (pts (xy 116.84 137.16) (xy 121.92 137.16))
    (stroke (width 0) (type default))
  )
  (wire (pts (xy 391.16 223.52) (xy 388.62 223.52))
    (stroke (width 0) (type default))
  )
  (wire (pts (xy 83.82 228.6) (xy 92.71 228.6))
    (stroke (width 0) (type default))
  )
  (wire (pts (xy 254 107.95) (xy 254 115.57))
    (stroke (width 0) (type default))
  )
  (wire (pts (xy 254 33.02) (xy 254 40.64))
    (stroke (width 0) (type default))
  )
  (wire (pts (xy 388.62 152.4) (xy 381 152.4))
    (stroke (width 0) (type default))
  )
  (wire (pts (xy 353.06 191.77) (xy 353.06 189.23))
    (stroke (width 0) (type default))
  )
  (wire (pts (xy 347.98 46.99) (xy 350.52 46.99))
    (stroke (width 0) (type default))
  )
  (wire (pts (xy 254 245.11) (xy 254 242.57))
    (stroke (width 0) (type default))
  )
  (wire (pts (xy 87.63 55.88) (xy 87.63 60.96))
    (stroke (width 0) (type default))
  )
  (wire (pts (xy 121.92 147.32) (xy 119.38 147.32))
    (stroke (width 0) (type default))
  )
  (wire (pts (xy 397.51 130.81) (xy 397.51 132.08))
    (stroke (width 0) (type default))
  )
  (wire (pts (xy 372.11 132.08) (xy 381 132.08))
    (stroke (width 0) (type default))
  )
  (wire (pts (xy 353.06 199.39) (xy 353.06 191.77))
    (stroke (width 0) (type default))
  )
  (wire (pts (xy 356.87 43.18) (xy 356.87 48.26))
    (stroke (width 0) (type default))
  )
  (wire (pts (xy 397.51 179.07) (xy 396.24 179.07))
    (stroke (width 0) (type default))
  )
  (wire (pts (xy 372.11 242.57) (xy 372.11 243.84))
    (stroke (width 0) (type default))
  )
  (wire (pts (xy 254 130.81) (xy 254 128.27))
    (stroke (width 0) (type default))
  )
  (wire (pts (xy 364.49 231.14) (xy 364.49 234.95))
    (stroke (width 0) (type default))
  )
  (wire (pts (xy 314.96 168.91) (xy 314.96 179.07))
    (stroke (width 0) (type default))
  )
  (wire (pts (xy 198.12 127) (xy 198.12 135.89))
    (stroke (width 0) (type default))
  )
  (wire (pts (xy 364.49 132.08) (xy 372.11 132.08))
    (stroke (width 0) (type default))
  )
  (wire (pts (xy 80.01 127) (xy 86.36 127))
    (stroke (width 0) (type default))
  )
  (wire (pts (xy 44.45 38.1) (xy 48.26 38.1))
    (stroke (width 0) (type default))
  )
  (wire (pts (xy 254 185.42) (xy 254 193.04))
    (stroke (width 0) (type default))
  )
  (wire (pts (xy 43.18 40.64) (xy 40.64 40.64))
    (stroke (width 0) (type default))
  )
  (wire (pts (xy 388.62 191.77) (xy 388.62 199.39))
    (stroke (width 0) (type default))
  )
  (wire (pts (xy 360.68 229.87) (xy 350.52 229.87))
    (stroke (width 0) (type default))
  )
  (wire (pts (xy 364.49 223.52) (xy 372.11 223.52))
    (stroke (width 0) (type default))
  )
  (wire (pts (xy 180.34 127) (xy 180.34 128.27))
    (stroke (width 0) (type default))
  )
  (wire (pts (xy 101.6 223.52) (xy 116.84 223.52))
    (stroke (width 0) (type default))
  )
  (wire (pts (xy 119.38 144.78) (xy 121.92 144.78))
    (stroke (width 0) (type default))
  )
  (wire (pts (xy 158.75 64.77) (xy 158.75 66.04))
    (stroke (width 0) (type default))
  )
  (wire (pts (xy 388.62 132.08) (xy 388.62 139.7))
    (stroke (width 0) (type default))
  )
  (wire (pts (xy 190.5 64.77) (xy 199.39 64.77))
    (stroke (width 0) (type default))
  )

  (text "2V5 Supply" (at 324.485 27.305 0)
    (effects (font (size 2.9972 2.9972)) (justify left bottom))
  )
  (text "SOURCE:Trelis board" (at 118.11 161.925 0)
    (effects (font (size 1.27 1.27)) (justify left bottom))
  )
  (text "1V8 supply" (at 328.93 120.015 0)
    (effects (font (size 2.9972 2.9972)) (justify left bottom))
  )
  (text "1.0V/3A" (at 400.05 222.25 0)
    (effects (font (size 1.27 1.27)) (justify left bottom))
  )
  (text "AUX supply connector" (at 26.035 26.67 0)
    (effects (font (size 2.9972 2.9972)) (justify left bottom))
  )
  (text "Delay capacitor calculated \nfor 0-1.22V change via 100k to 5V\n(now set as ~{} 0.26s delay)"
    (at 52.705 250.825 0)
    (effects (font (size 1.27 1.27)) (justify right bottom))
  )
  (text "SOURCE:Trelis board" (at 328.93 103.505 0)
    (effects (font (size 1.27 1.27)) (justify left bottom))
  )
  (text "1.35V/3A" (at 398.78 177.8 0)
    (effects (font (size 1.27 1.27)) (justify left bottom))
  )
  (text "SOURCE:Trelis board" (at 330.2 243.205 0)
    (effects (font (size 1.27 1.27)) (justify left bottom))
  )
  (text "1.8V/3A" (at 398.78 130.175 0)
    (effects (font (size 1.27 1.27)) (justify left bottom))
  )
  (text "STEP1: 1V2, 1V0\nSTEP2: 3V3, 1V8, 1V35\nSTEP3: 2V5\nSource: Trellis"
    (at 92.075 238.125 0)
    (effects (font (size 1.27 1.27)) (justify left bottom))
  )
  (text "Battery connector" (at 148.59 208.915 0)
    (effects (font (size 2.9972 2.9972)) (justify left bottom))
  )
  (text "Power sequencer" (at 57.15 194.945 0)
    (effects (font (size 2.9972 2.9972)) (justify left bottom))
  )
  (text "3V3 supply" (at 325.755 73.66 0)
    (effects (font (size 2.9972 2.9972)) (justify left bottom))
  )
  (text "3V3 levels required by I2C translator" (at 214.63 107.95 0)
    (effects (font (size 1.27 1.27)) (justify left bottom))
  )
  (text "1V2 Supply" (at 119.38 116.205 0)
    (effects (font (size 2.9972 2.9972)) (justify left bottom))
  )
  (text "1V35 supply" (at 326.39 169.545 0)
    (effects (font (size 2.9972 2.9972)) (justify left bottom))
  )
  (text "SOURCE:Trelis board" (at 329.565 152.4 0)
    (effects (font (size 1.27 1.27)) (justify left bottom))
  )
  (text "1V0 supply" (at 326.39 213.995 0)
    (effects (font (size 2.9972 2.9972)) (justify left bottom))
  )
  (text "SOURCE:Trelis board" (at 331.47 198.12 0)
    (effects (font (size 1.27 1.27)) (justify left bottom))
  )
  (text "MainSupply (5V 5A)" (at 118.11 21.59 0)
    (effects (font (size 2.9972 2.9972)) (justify left bottom))
  )
  (text "2.5V/3A" (at 400.05 35.56 0)
    (effects (font (size 1.27 1.27)) (justify left bottom))
  )
  (text "PWR_LED Indicators" (at 230.505 20.32 0)
    (effects (font (size 2.9972 2.9972)) (justify left bottom))
  )
  (text "3.3V/3A" (at 398.78 82.55 0)
    (effects (font (size 1.27 1.27)) (justify left bottom))
  )

  (label "1V35_PG" (at 322.58 191.77 0) (fields_autoplaced)
    (effects (font (size 1.27 1.27)) (justify left bottom))
  )
  (label "5V0_PG" (at 34.29 226.06 0) (fields_autoplaced)
    (effects (font (size 1.27 1.27)) (justify left bottom))
  )
  (label "VCCIO_EN" (at 320.04 138.43 0) (fields_autoplaced)
    (effects (font (size 1.27 1.27)) (justify left bottom))
  )
  (label "VCCAUX_EN" (at 316.23 43.18 0) (fields_autoplaced)
    (effects (font (size 1.27 1.27)) (justify left bottom))
  )
  (label "3V3_PG" (at 229.87 241.3 0) (fields_autoplaced)
    (effects (font (size 1.27 1.27)) (justify left bottom))
  )
  (label "1V0_PG" (at 322.58 236.22 0) (fields_autoplaced)
    (effects (font (size 1.27 1.27)) (justify left bottom))
  )
  (label "5V0_PG" (at 144.78 50.8 0) (fields_autoplaced)
    (effects (font (size 1.27 1.27)) (justify left bottom))
  )
  (label "5V0_PG" (at 229.87 162.56 0) (fields_autoplaced)
    (effects (font (size 1.27 1.27)) (justify left bottom))
  )
  (label "1V8_PG" (at 231.14 52.07 0) (fields_autoplaced)
    (effects (font (size 1.27 1.27)) (justify left bottom))
  )
  (label "VCCIO_EN" (at 115.57 226.06 180) (fields_autoplaced)
    (effects (font (size 1.27 1.27)) (justify right bottom))
  )
  (label "VCCAUX_EN" (at 115.57 228.6 180) (fields_autoplaced)
    (effects (font (size 1.27 1.27)) (justify right bottom))
  )
  (label "1V2_PG" (at 149.86 139.7 180) (fields_autoplaced)
    (effects (font (size 1.27 1.27)) (justify right bottom))
  )
  (label "VCCIO_EN" (at 318.77 90.17 0) (fields_autoplaced)
    (effects (font (size 1.27 1.27)) (justify left bottom))
  )
  (label "3V3_PG" (at 321.31 96.52 0) (fields_autoplaced)
    (effects (font (size 1.27 1.27)) (justify left bottom))
  )
  (label "VCCA0_EN" (at 110.49 134.62 0) (fields_autoplaced)
    (effects (font (size 1.27 1.27)) (justify left bottom))
  )
  (label "2V5_PG" (at 320.04 49.53 0) (fields_autoplaced)
    (effects (font (size 1.27 1.27)) (justify left bottom))
  )
  (label "2V5_PG" (at 229.87 275.59 0) (fields_autoplaced)
    (effects (font (size 1.27 1.27)) (justify left bottom))
  )
  (label "VCCIO_EN" (at 320.04 185.42 0) (fields_autoplaced)
    (effects (font (size 1.27 1.27)) (justify left bottom))
  )
  (label "1V2_PG" (at 229.87 204.47 0) (fields_autoplaced)
    (effects (font (size 1.27 1.27)) (justify left bottom))
  )
  (label "VCCA0_EN" (at 320.04 229.87 0) (fields_autoplaced)
    (effects (font (size 1.27 1.27)) (justify left bottom))
  )
  (label "1V8_PG" (at 322.58 144.78 0) (fields_autoplaced)
    (effects (font (size 1.27 1.27)) (justify left bottom))
  )
  (label "VCCA0_EN" (at 115.57 223.52 180) (fields_autoplaced)
    (effects (font (size 1.27 1.27)) (justify right bottom))
  )
  (label "1V35_PG" (at 228.6 88.9 0) (fields_autoplaced)
    (effects (font (size 1.27 1.27)) (justify left bottom))
  )

  (global_label "VCC5V0" (shape input) (at 81.28 118.11 180) (fields_autoplaced)
    (effects (font (size 1.27 1.27)) (justify right))
    (property "Intersheetrefs" "${INTERSHEET_REFS}" (at 0 0 0)
      (effects (font (size 1.27 1.27)) hide)
    )
  )
  (global_label "VCC5V0" (shape input) (at 90.17 208.28 90) (fields_autoplaced)
    (effects (font (size 1.27 1.27)) (justify left))
    (property "Intersheetrefs" "${INTERSHEET_REFS}" (at 8.89 0 0)
      (effects (font (size 1.27 1.27)) hide)
    )
  )
  (global_label "VCC3V3" (shape input) (at 276.86 69.85 0) (fields_autoplaced)
    (effects (font (size 1.27 1.27)) (justify left))
    (property "Intersheetrefs" "${INTERSHEET_REFS}" (at 0.635 0.635 0)
      (effects (font (size 1.27 1.27)) hide)
    )
  )
  (global_label "VCC1V35" (shape input) (at 397.51 179.07 0) (fields_autoplaced)
    (effects (font (size 1.27 1.27)) (justify left))
    (property "Intersheetrefs" "${INTERSHEET_REFS}" (at 408.1867 179.07 0)
      (effects (font (size 1.27 1.27)) (justify left) hide)
    )
  )
  (global_label "VCC5V0" (shape input) (at 314.96 121.92 180) (fields_autoplaced)
    (effects (font (size 1.27 1.27)) (justify right))
    (property "Intersheetrefs" "${INTERSHEET_REFS}" (at 0.635 0.635 0)
      (effects (font (size 1.27 1.27)) hide)
    )
  )
  (global_label "P12V_AUX" (shape input) (at 31.75 69.85 180) (fields_autoplaced)
    (effects (font (size 1.27 1.27)) (justify right))
    (property "Intersheetrefs" "${INTERSHEET_REFS}" (at 0.635 0.635 0)
      (effects (font (size 1.27 1.27)) hide)
    )
  )
  (global_label "VCC5V0" (shape input) (at 237.49 187.96 180) (fields_autoplaced)
    (effects (font (size 1.27 1.27)) (justify right))
    (property "Intersheetrefs" "${INTERSHEET_REFS}" (at 4.445 14.605 0)
      (effects (font (size 1.27 1.27)) hide)
    )
  )
  (global_label "VCC5V0" (shape input) (at 314.96 168.91 180) (fields_autoplaced)
    (effects (font (size 1.27 1.27)) (justify right))
    (property "Intersheetrefs" "${INTERSHEET_REFS}" (at 0.635 0.635 0)
      (effects (font (size 1.27 1.27)) hide)
    )
  )
  (global_label "VCC5V0" (shape input) (at 312.42 73.66 180) (fields_autoplaced)
    (effects (font (size 1.27 1.27)) (justify right))
    (property "Intersheetrefs" "${INTERSHEET_REFS}" (at -1.27 0 0)
      (effects (font (size 1.27 1.27)) hide)
    )
  )
  (global_label "VCC5V0" (shape input) (at 236.22 72.39 180) (fields_autoplaced)
    (effects (font (size 1.27 1.27)) (justify right))
    (property "Intersheetrefs" "${INTERSHEET_REFS}" (at 0 1.905 0)
      (effects (font (size 1.27 1.27)) hide)
    )
  )
  (global_label "VCC12V" (shape input) (at 115.57 40.64 90) (fields_autoplaced)
    (effects (font (size 1.27 1.27)) (justify left))
    (property "Intersheetrefs" "${INTERSHEET_REFS}" (at -4.445 3.175 0)
      (effects (font (size 1.27 1.27)) hide)
    )
  )
  (global_label "VCC5V0" (shape input) (at 314.96 213.36 180) (fields_autoplaced)
    (effects (font (size 1.27 1.27)) (justify right))
    (property "Intersheetrefs" "${INTERSHEET_REFS}" (at 0.635 0.635 0)
      (effects (font (size 1.27 1.27)) hide)
    )
  )
  (global_label "P12V_AUX" (shape input) (at 48.26 38.1 0) (fields_autoplaced)
    (effects (font (size 1.27 1.27)) (justify left))
    (property "Intersheetrefs" "${INTERSHEET_REFS}" (at 80.01 -0.635 0)
      (effects (font (size 1.27 1.27)) hide)
    )
  )
  (global_label "3V0_BAT" (shape input) (at 154.94 218.44 180) (fields_autoplaced)
    (effects (font (size 1.27 1.27)) (justify right))
    (property "Intersheetrefs" "${INTERSHEET_REFS}" (at 2.54 -32.385 0)
      (effects (font (size 1.27 1.27)) hide)
    )
  )
  (global_label "VCC5V0" (shape input) (at 48.26 208.28 90) (fields_autoplaced)
    (effects (font (size 1.27 1.27)) (justify left))
    (property "Intersheetrefs" "${INTERSHEET_REFS}" (at 3.175 -0.635 0)
      (effects (font (size 1.27 1.27)) hide)
    )
  )
  (global_label "VCC12V" (shape input) (at 78.74 55.88 90) (fields_autoplaced)
    (effects (font (size 1.27 1.27)) (justify left))
    (property "Intersheetrefs" "${INTERSHEET_REFS}" (at 0 0 0)
      (effects (font (size 1.27 1.27)) hide)
    )
  )
  (global_label "VCC1V0" (shape input) (at 398.78 223.52 0) (fields_autoplaced)
    (effects (font (size 1.27 1.27)) (justify left))
    (property "Intersheetrefs" "${INTERSHEET_REFS}" (at 408.2472 223.52 0)
      (effects (font (size 1.27 1.27)) (justify left) hide)
    )
  )
  (global_label "VCC2V5" (shape input) (at 398.78 36.83 0) (fields_autoplaced)
    (effects (font (size 1.27 1.27)) (justify left))
    (property "Intersheetrefs" "${INTERSHEET_REFS}" (at 408.2472 36.83 0)
      (effects (font (size 1.27 1.27)) (justify left) hide)
    )
  )
  (global_label "VCC5V0" (shape input) (at 212.09 53.34 0) (fields_autoplaced)
    (effects (font (size 1.27 1.27)) (justify left))
    (property "Intersheetrefs" "${INTERSHEET_REFS}" (at 221.5572 53.34 0)
      (effects (font (size 1.27 1.27)) (justify left) hide)
    )
  )
  (global_label "VCC5V0" (shape input) (at 237.49 35.56 180) (fields_autoplaced)
    (effects (font (size 1.27 1.27)) (justify right))
    (property "Intersheetrefs" "${INTERSHEET_REFS}" (at 1.27 1.27 0)
      (effects (font (size 1.27 1.27)) hide)
    )
  )
  (global_label "VCC12V" (shape input) (at 87.63 55.88 90) (fields_autoplaced)
    (effects (font (size 1.27 1.27)) (justify left))
    (property "Intersheetrefs" "${INTERSHEET_REFS}" (at 0 0 0)
      (effects (font (size 1.27 1.27)) hide)
    )
  )
  (global_label "VCC3V3" (shape input) (at 236.22 110.49 180) (fields_autoplaced)
    (effects (font (size 1.27 1.27)) (justify right))
    (property "Intersheetrefs" "${INTERSHEET_REFS}" (at 2.54 1.905 0)
      (effects (font (size 1.27 1.27)) hide)
    )
  )
  (global_label "1V0_PG" (shape input) (at 236.22 127 180) (fields_autoplaced)
    (effects (font (size 1.27 1.27)) (justify right))
    (property "Intersheetrefs" "${INTERSHEET_REFS}" (at 2.54 1.905 0)
      (effects (font (size 1.27 1.27)) hide)
    )
  )
  (global_label "VCC1V8" (shape input) (at 398.78 132.08 0) (fields_autoplaced)
    (effects (font (size 1.27 1.27)) (justify left))
    (property "Intersheetrefs" "${INTERSHEET_REFS}" (at 408.2472 132.08 0)
      (effects (font (size 1.27 1.27)) (justify left) hide)
    )
  )
  (global_label "VCC12V" (shape input) (at 96.52 55.88 90) (fields_autoplaced)
    (effects (font (size 1.27 1.27)) (justify left))
    (property "Intersheetrefs" "${INTERSHEET_REFS}" (at 0 0 0)
      (effects (font (size 1.27 1.27)) hide)
    )
  )
  (global_label "VCC3V3" (shape input) (at 276.86 33.02 0) (fields_autoplaced)
    (effects (font (size 1.27 1.27)) (justify left))
    (property "Intersheetrefs" "${INTERSHEET_REFS}" (at 1.27 0 0)
      (effects (font (size 1.27 1.27)) hide)
    )
  )
  (global_label "VCC3V3" (shape input) (at 397.51 83.82 0) (fields_autoplaced)
    (effects (font (size 1.27 1.27)) (justify left))
    (property "Intersheetrefs" "${INTERSHEET_REFS}" (at 406.9772 83.82 0)
      (effects (font (size 1.27 1.27)) (justify left) hide)
    )
  )
  (global_label "VCC3V3" (shape input) (at 276.86 107.95 0) (fields_autoplaced)
    (effects (font (size 1.27 1.27)) (justify left))
    (property "Intersheetrefs" "${INTERSHEET_REFS}" (at 3.175 0.635 0)
      (effects (font (size 1.27 1.27)) hide)
    )
  )
  (global_label "VCC5V0" (shape input) (at 110.49 115.57 180) (fields_autoplaced)
    (effects (font (size 1.27 1.27)) (justify right))
    (property "Intersheetrefs" "${INTERSHEET_REFS}" (at 0 0 0)
      (effects (font (size 1.27 1.27)) hide)
    )
  )
  (global_label "VCC12V" (shape input) (at 57.15 69.85 0) (fields_autoplaced)
    (effects (font (size 1.27 1.27)) (justify left))
    (property "Intersheetrefs" "${INTERSHEET_REFS}" (at 0 0.635 0)
      (effects (font (size 1.27 1.27)) hide)
    )
  )
  (global_label "VCC5V0" (shape input) (at 236.22 259.08 180) (fields_autoplaced)
    (effects (font (size 1.27 1.27)) (justify right))
    (property "Intersheetrefs" "${INTERSHEET_REFS}" (at 2.54 12.065 0)
      (effects (font (size 1.27 1.27)) hide)
    )
  )
  (global_label "VCC3V3" (shape input) (at 276.86 146.05 0) (fields_autoplaced)
    (effects (font (size 1.27 1.27)) (justify left))
    (property "Intersheetrefs" "${INTERSHEET_REFS}" (at 3.175 8.255 0)
      (effects (font (size 1.27 1.27)) hide)
    )
  )
  (global_label "VCC3V3" (shape input) (at 276.86 256.54 0) (fields_autoplaced)
    (effects (font (size 1.27 1.27)) (justify left))
    (property "Intersheetrefs" "${INTERSHEET_REFS}" (at 3.175 10.795 0)
      (effects (font (size 1.27 1.27)) hide)
    )
  )
  (global_label "VCC3V3" (shape input) (at 276.86 185.42 0) (fields_autoplaced)
    (effects (font (size 1.27 1.27)) (justify left))
    (property "Intersheetrefs" "${INTERSHEET_REFS}" (at 3.81 13.335 0)
      (effects (font (size 1.27 1.27)) hide)
    )
  )
  (global_label "VCC5V0" (shape input) (at 236.22 224.79 180) (fields_autoplaced)
    (effects (font (size 1.27 1.27)) (justify right))
    (property "Intersheetrefs" "${INTERSHEET_REFS}" (at 2.54 16.51 0)
      (effects (font (size 1.27 1.27)) hide)
    )
  )
  (global_label "VCC1V2" (shape input) (at 210.82 127 0) (fields_autoplaced)
    (effects (font (size 1.27 1.27)) (justify left))
    (property "Intersheetrefs" "${INTERSHEET_REFS}" (at 220.2872 127 0)
      (effects (font (size 1.27 1.27)) (justify left) hide)
    )
  )
  (global_label "VCC5V0" (shape input) (at 62.23 208.28 90) (fields_autoplaced)
    (effects (font (size 1.27 1.27)) (justify left))
    (property "Intersheetrefs" "${INTERSHEET_REFS}" (at 10.16 -0.635 0)
      (effects (font (size 1.27 1.27)) hide)
    )
  )
  (global_label "VCC5V0" (shape input) (at 312.42 26.67 180) (fields_autoplaced)
    (effects (font (size 1.27 1.27)) (justify right))
    (property "Intersheetrefs" "${INTERSHEET_REFS}" (at 0.635 0 0)
      (effects (font (size 1.27 1.27)) hide)
    )
  )
  (global_label "VCC3V3" (shape input) (at 276.86 222.25 0) (fields_autoplaced)
    (effects (font (size 1.27 1.27)) (justify left))
    (property "Intersheetrefs" "${INTERSHEET_REFS}" (at 3.175 15.24 0)
      (effects (font (size 1.27 1.27)) hide)
    )
  )

  (symbol (lib_id "antmicropower:GND") (at 313.69 105.41 0) (unit 1)
    (in_bom yes) (on_board yes) (dnp no)
    (property "Reference" "#PWR085" (at 313.69 111.76 0)
      (effects (font (size 1.27 1.27)) hide)
    )
    (property "Value" "GND" (at 313.817 109.8042 0)
      (effects (font (size 1.27 1.27)))
    )
    (property "Footprint" "" (at 313.69 105.41 0)
      (effects (font (size 1.27 1.27)) hide)
    )
    (property "Datasheet" "" (at 313.69 105.41 0)
      (effects (font (size 1.27 1.27)) hide)
    )
    (property "Author" "Antmicro" (at 322.58 113.03 0)
      (effects (font (size 1.27 1.27) (thickness 0.15)) (justify left bottom) hide)
    )
    (property "License" "Apache-2.0" (at 322.58 115.57 0)
      (effects (font (size 1.27 1.27) (thickness 0.15)) (justify left bottom) hide)
    )
    (pin "1")
    (instances
      (project "ecp5-dc-scm"
        (path ""
          (reference "#PWR085") (unit 1)
        )
      )
    )
  )

  (symbol (lib_id "antmicropower:GND") (at 351.79 105.41 0) (unit 1)
    (in_bom yes) (on_board yes) (dnp no)
    (property "Reference" "#PWR090" (at 351.79 111.76 0)
      (effects (font (size 1.27 1.27)) hide)
    )
    (property "Value" "GND" (at 351.917 109.8042 0)
      (effects (font (size 1.27 1.27)))
    )
    (property "Footprint" "" (at 351.79 105.41 0)
      (effects (font (size 1.27 1.27)) hide)
    )
    (property "Datasheet" "" (at 351.79 105.41 0)
      (effects (font (size 1.27 1.27)) hide)
    )
    (property "Author" "Antmicro" (at 360.68 113.03 0)
      (effects (font (size 1.27 1.27) (thickness 0.15)) (justify left bottom) hide)
    )
    (property "License" "Apache-2.0" (at 360.68 115.57 0)
      (effects (font (size 1.27 1.27) (thickness 0.15)) (justify left bottom) hide)
    )
    (pin "1")
    (instances
      (project "ecp5-dc-scm"
        (path ""
          (reference "#PWR090") (unit 1)
        )
      )
    )
  )

  (symbol (lib_id "antmicroFuses:F_3A_1206") (at 43.18 69.85 0) (unit 1)
    (in_bom yes) (on_board yes) (dnp no)
    (property "Reference" "F1" (at 45.72 67.31 0)
      (effects (font (size 1.27 1.27)))
    )
    (property "Value" "0466003.NR" (at 45.72 72.39 0)
      (effects (font (size 1.27 1.27)))
    )
    (property "Footprint" "antmicro-footprints:F_1206_3216Metric" (at 43.18 62.23 0)
      (effects (font (size 1.27 1.27)) (justify left) hide)
    )
    (property "Datasheet" "https://www.littelfuse.com/~/media/electronics/datasheets/fuses/littelfuse_fuse_466_datasheet.pdf.pdf" (at 43.18 57.15 0)
      (effects (font (size 1.27 1.27)) (justify left) hide)
    )
    (property "Manufacturer" "Littelfuse" (at 43.18 57.15 0)
      (effects (font (size 1.27 1.27)) (justify left) hide)
    )
    (property "MPN" "0466003.NR " (at 49.53 59.69 0)
      (effects (font (size 1.27 1.27)) hide)
    )
    (property "Author" "Antmicro" (at 63.5 90.17 0)
      (effects (font (size 1.27 1.27) (thickness 0.15)) (justify left bottom) hide)
    )
    (property "License" "Apache-2.0" (at 63.5 92.71 0)
      (effects (font (size 1.27 1.27) (thickness 0.15)) (justify left bottom) hide)
    )
    (pin "1")
    (pin "2")
    (instances
      (project "ecp5-dc-scm"
        (path ""
          (reference "F1") (unit 1)
        )
      )
    )
  )

  (symbol (lib_id "antmicropower:GND") (at 157.48 226.06 0) (mirror y) (unit 1)
    (in_bom yes) (on_board yes) (dnp no)
    (property "Reference" "#PWR076" (at 157.48 232.41 0)
      (effects (font (size 1.27 1.27)) hide)
    )
    (property "Value" "GND" (at 157.353 230.4542 0)
      (effects (font (size 1.27 1.27)))
    )
    (property "Footprint" "" (at 157.48 226.06 0)
      (effects (font (size 1.27 1.27)) hide)
    )
    (property "Datasheet" "" (at 157.48 226.06 0)
      (effects (font (size 1.27 1.27)) hide)
    )
    (property "Author" "Antmicro" (at 148.59 233.68 0)
      (effects (font (size 1.27 1.27) (thickness 0.15)) (justify left bottom) hide)
    )
    (property "License" "Apache-2.0" (at 148.59 236.22 0)
      (effects (font (size 1.27 1.27) (thickness 0.15)) (justify left bottom) hide)
    )
    (pin "1")
    (instances
      (project "ecp5-dc-scm"
        (path ""
          (reference "#PWR076") (unit 1)
        )
      )
    )
  )

  (symbol (lib_id "antmicroResistorsmisc:R_0R_1206") (at 207.01 53.34 180) (unit 1)
    (in_bom yes) (on_board yes) (dnp no)
    (property "Reference" "R94" (at 204.47 50.8 0)
      (effects (font (size 1.524 1.524)))
    )
    (property "Value" "R_0R_1206" (at 207.01 49.53 0)
      (effects (font (size 1.524 1.524)) hide)
    )
    (property "Footprint" "antmicro-footprints:R_1206_3216Metric" (at 201.93 58.42 0)
      (effects (font (size 1.524 1.524)) (justify left) hide)
    )
    (property "Datasheet" "https://www.farnell.com/datasheets/2860635.pdf" (at 207.01 53.34 0)
      (effects (font (size 1.27 1.27)) hide)
    )
    (property "Manufacturer" "Multicomp Pro" (at 201.93 63.5 0)
      (effects (font (size 1.524 1.524)) (justify left) hide)
    )
    (property "MPN" "MCMR12X000_PTL" (at 201.93 60.96 0)
      (effects (font (size 1.524 1.524)) (justify left) hide)
    )
    (property "Val" "0R" (at 204.47 53.34 0)
      (effects (font (size 1.27 1.27)))
    )
    (property "License" "Apache-2.0" (at 186.69 27.94 0)
      (effects (font (size 1.27 1.27) (thickness 0.15)) (justify left bottom) hide)
    )
    (property "Author" "Antmicro" (at 186.69 25.4 0)
      (effects (font (size 1.27 1.27) (thickness 0.15)) (justify left bottom) hide)
    )
    (property "Tolerance" "~" (at 186.69 43.18 0)
      (effects (font (size 1.27 1.27)) (justify left bottom) hide)
    )
    (property "Current" "2A" (at 186.69 22.86 0)
      (effects (font (size 1.27 1.27) (thickness 0.15)) (justify left bottom) hide)
    )
    (property "Public" "False" (at 186.69 22.86 0)
      (effects (font (size 1.27 1.27)) (justify left bottom) hide)
    )
    (pin "1")
    (pin "2")
    (instances
      (project "ecp5-dc-scm"
        (path ""
          (reference "R94") (unit 1)
        )
      )
    )
  )

  (symbol (lib_id "antmicropower:GND") (at 312.42 58.42 0) (unit 1)
    (in_bom yes) (on_board yes) (dnp no)
    (property "Reference" "#PWR084" (at 312.42 64.77 0)
      (effects (font (size 1.27 1.27)) hide)
    )
    (property "Value" "GND" (at 312.547 62.8142 0)
      (effects (font (size 1.27 1.27)))
    )
    (property "Footprint" "" (at 312.42 58.42 0)
      (effects (font (size 1.27 1.27)) hide)
    )
    (property "Datasheet" "" (at 312.42 58.42 0)
      (effects (font (size 1.27 1.27)) hide)
    )
    (property "Author" "Antmicro" (at 321.31 66.04 0)
      (effects (font (size 1.27 1.27) (thickness 0.15)) (justify left bottom) hide)
    )
    (property "License" "Apache-2.0" (at 321.31 68.58 0)
      (effects (font (size 1.27 1.27) (thickness 0.15)) (justify left bottom) hide)
    )
    (pin "1")
    (instances
      (project "ecp5-dc-scm"
        (path ""
          (reference "#PWR084") (unit 1)
        )
      )
    )
  )

  (symbol (lib_id "antmicropower:GND") (at 350.52 58.42 0) (unit 1)
    (in_bom yes) (on_board yes) (dnp no)
    (property "Reference" "#PWR089" (at 350.52 64.77 0)
      (effects (font (size 1.27 1.27)) hide)
    )
    (property "Value" "GND" (at 350.647 62.8142 0)
      (effects (font (size 1.27 1.27)))
    )
    (property "Footprint" "" (at 350.52 58.42 0)
      (effects (font (size 1.27 1.27)) hide)
    )
    (property "Datasheet" "" (at 350.52 58.42 0)
      (effects (font (size 1.27 1.27)) hide)
    )
    (property "Author" "Antmicro" (at 359.41 66.04 0)
      (effects (font (size 1.27 1.27) (thickness 0.15)) (justify left bottom) hide)
    )
    (property "License" "Apache-2.0" (at 359.41 68.58 0)
      (effects (font (size 1.27 1.27) (thickness 0.15)) (justify left bottom) hide)
    )
    (pin "1")
    (instances
      (project "ecp5-dc-scm"
        (path ""
          (reference "#PWR089") (unit 1)
        )
      )
    )
  )

  (symbol (lib_id "antmicropower:GND") (at 254 279.4 0) (unit 1)
    (in_bom yes) (on_board yes) (dnp no)
    (property "Reference" "#PWR081" (at 254 285.75 0)
      (effects (font (size 1.27 1.27)) hide)
    )
    (property "Value" "GND" (at 254.127 283.7942 0)
      (effects (font (size 1.27 1.27)))
    )
    (property "Footprint" "" (at 254 279.4 0)
      (effects (font (size 1.27 1.27)) hide)
    )
    (property "Datasheet" "" (at 254 279.4 0)
      (effects (font (size 1.27 1.27)) hide)
    )
    (property "Author" "Antmicro" (at 262.89 287.02 0)
      (effects (font (size 1.27 1.27) (thickness 0.15)) (justify left bottom) hide)
    )
    (property "License" "Apache-2.0" (at 262.89 289.56 0)
      (effects (font (size 1.27 1.27) (thickness 0.15)) (justify left bottom) hide)
    )
    (pin "1")
    (instances
      (project "ecp5-dc-scm"
        (path ""
          (reference "#PWR081") (unit 1)
        )
      )
    )
  )

  (symbol (lib_id "antmicroCapacitors0402:C_10u_0402") (at 312.42 44.45 90) (unit 1)
    (in_bom yes) (on_board yes) (dnp no) (fields_autoplaced)
    (property "Reference" "C113" (at 309.88 40.6336 90)
      (effects (font (size 1.524 1.524)) (justify left))
    )
    (property "Value" "C_10u_0402" (at 316.23 44.45 0)
      (effects (font (size 1.524 1.524)) hide)
    )
    (property "Footprint" "antmicro-footprints:C_0402_1005Metric" (at 307.34 39.37 0)
      (effects (font (size 1.524 1.524)) (justify left) hide)
    )
    (property "Datasheet" "https://www.yageo.com/en/Chart/Download/pdf/CC0402MRX5R5BB106" (at 312.42 44.45 0)
      (effects (font (size 1.27 1.27)) hide)
    )
    (property "Manufacturer" "YAGEO" (at 302.26 39.37 0)
      (effects (font (size 1.524 1.524)) (justify left) hide)
    )
    (property "MPN" "CC0402MRX5R5BB106" (at 304.8 39.37 0)
      (effects (font (size 1.524 1.524)) (justify left) hide)
    )
    (property "Val" "10u" (at 309.88 43.1736 90)
      (effects (font (size 1.27 1.27)) (justify left))
    )
    (property "License" "Apache-2.0" (at 335.28 24.13 0)
      (effects (font (size 1.27 1.27) (thickness 0.15)) (justify left bottom) hide)
    )
    (property "Author" "Antmicro" (at 337.82 24.13 0)
      (effects (font (size 1.27 1.27) (thickness 0.15)) (justify left bottom) hide)
    )
    (property "Voltage" "" (at 340.36 24.13 0)
      (effects (font (size 1.27 1.27)) (justify left bottom) hide)
    )
    (property "Dielectric" "" (at 342.9 24.13 0)
      (effects (font (size 1.27 1.27)) (justify left bottom) hide)
    )
    (property "Public" "False" (at 345.44 24.13 0)
      (effects (font (size 1.27 1.27)) (justify left bottom) hide)
    )
    (pin "1")
    (pin "2")
    (instances
      (project "ecp5-dc-scm"
        (path ""
          (reference "C113") (unit 1)
        )
      )
    )
  )

  (symbol (lib_id "antmicroDCDCConverters:TPS62823DLCT") (at 327.66 36.83 0) (unit 1)
    (in_bom yes) (on_board yes) (dnp no) (fields_autoplaced)
    (property "Reference" "U16" (at 337.82 29.21 0)
      (effects (font (size 1.27 1.27)))
    )
    (property "Value" "TPS62823DLCT" (at 337.82 31.75 0)
      (effects (font (size 1.27 1.27)))
    )
    (property "Footprint" "antmicro-footprints:QFN-8_2x1.5mm" (at 325.12 41.91 0)
      (effects (font (size 1.27 1.27)) hide)
    )
    (property "Datasheet" "https://www.ti.com/lit/ds/symlink/tps62823.pdf?ts=1685970309606&ref_url=https%253A%252F%252Fwww.ti.com%252Fproduct%252FTPS62823%252Fpart-details%252FTPS62823DLCT" (at 327.66 39.37 0)
      (effects (font (size 1.27 1.27)) hide)
    )
    (property "MPN" "TPS62823DLCT" (at 328.93 17.399 0)
      (effects (font (size 1.27 1.27)) hide)
    )
    (property "Manufacturer" "Texas Instruments" (at 328.93 19.7104 0)
      (effects (font (size 1.27 1.27)) hide)
    )
    (property "Author" "Antmicro" (at 361.95 50.8 0)
      (effects (font (size 1.27 1.27) (thickness 0.15)) (justify left bottom) hide)
    )
    (property "License" "Apache-2.0" (at 361.95 53.34 0)
      (effects (font (size 1.27 1.27) (thickness 0.15)) (justify left bottom) hide)
    )
    (pin "1")
    (pin "2")
    (pin "3")
    (pin "5")
    (pin "6")
    (pin "7")
    (pin "8")
    (pin "4")
    (instances
      (project "ecp5-dc-scm"
        (path ""
          (reference "U16") (unit 1)
        )
      )
    )
  )

  (symbol (lib_id "antmicroCapacitors0402:C_120p_100V_0402") (at 365.76 44.45 90) (unit 1)
    (in_bom yes) (on_board yes) (dnp no) (fields_autoplaced)
    (property "Reference" "C122" (at 363.22 40.6336 90)
      (effects (font (size 1.524 1.524)) (justify left))
    )
    (property "Value" "C_120p_0402" (at 369.57 44.45 0)
      (effects (font (size 1.524 1.524)) hide)
    )
    (property "Footprint" "antmicro-footprints:C_0402_1005Metric" (at 360.68 39.37 0)
      (effects (font (size 1.524 1.524)) (justify left) hide)
    )
    (property "Datasheet" "https://www.kemet.com/en/us/capacitors/product/C0402C121J5GACTU.html" (at 365.76 44.45 0)
      (effects (font (size 1.27 1.27)) hide)
    )
    (property "Manufacturer" "KEMET" (at 355.6 39.37 0)
      (effects (font (size 1.524 1.524)) (justify left) hide)
    )
    (property "MPN" "C0402C121J5GACTU" (at 358.14 39.37 0)
      (effects (font (size 1.524 1.524)) (justify left) hide)
    )
    (property "Val" "120p" (at 363.22 43.1736 90)
      (effects (font (size 1.27 1.27)) (justify left))
    )
    (property "License" "Apache-2.0" (at 388.62 24.13 0)
      (effects (font (size 1.27 1.27) (thickness 0.15)) (justify left bottom) hide)
    )
    (property "Author" "Antmicro" (at 391.16 24.13 0)
      (effects (font (size 1.27 1.27) (thickness 0.15)) (justify left bottom) hide)
    )
    (property "Voltage" "100V" (at 393.7 24.13 0)
      (effects (font (size 1.27 1.27)) (justify left bottom) hide)
    )
    (property "Dielectric" "C0G" (at 396.24 24.13 0)
      (effects (font (size 1.27 1.27)) (justify left bottom) hide)
    )
    (property "Public" "False" (at 398.78 24.13 0)
      (effects (font (size 1.27 1.27)) (justify left bottom) hide)
    )
    (pin "1")
    (pin "2")
    (instances
      (project "ecp5-dc-scm"
        (path ""
          (reference "C122") (unit 1)
        )
      )
    )
  )

  (symbol (lib_id "antmicroResistors0402:R_100k_0402") (at 373.38 49.53 270) (unit 1)
    (in_bom yes) (on_board yes) (dnp no) (fields_autoplaced)
    (property "Reference" "R123" (at 375.92 50.8 90)
      (effects (font (size 1.524 1.524)) (justify left))
    )
    (property "Value" "R_100k_0402" (at 369.57 49.53 0)
      (effects (font (size 1.524 1.524)) hide)
    )
    (property "Footprint" "antmicro-footprints:R_0402_1005Metric" (at 378.46 54.61 0)
      (effects (font (size 1.524 1.524)) (justify left) hide)
    )
    (property "Datasheet" "https://www.bourns.com/docs/product-datasheets/cr.pdf" (at 373.38 49.53 0)
      (effects (font (size 1.27 1.27)) hide)
    )
    (property "Manufacturer" "Bourns" (at 383.54 54.61 0)
      (effects (font (size 1.524 1.524)) (justify left) hide)
    )
    (property "MPN" "CR0402-FX-1003GLF" (at 381 54.61 0)
      (effects (font (size 1.524 1.524)) (justify left) hide)
    )
    (property "Val" "100k" (at 375.92 53.34 90)
      (effects (font (size 1.27 1.27)) (justify left))
    )
    (property "License" "Apache-2.0" (at 347.98 69.85 0)
      (effects (font (size 1.27 1.27) (thickness 0.15)) (justify left bottom) hide)
    )
    (property "Author" "Antmicro" (at 345.44 69.85 0)
      (effects (font (size 1.27 1.27) (thickness 0.15)) (justify left bottom) hide)
    )
    (property "Tolerance" "1%" (at 363.22 69.85 0)
      (effects (font (size 1.27 1.27)) (justify left bottom) hide)
    )
    (property "Public" "False" (at 342.9 69.85 0)
      (effects (font (size 1.27 1.27)) (justify left bottom) hide)
    )
    (pin "1")
    (pin "2")
    (instances
      (project "ecp5-dc-scm"
        (path ""
          (reference "R123") (unit 1)
        )
      )
    )
  )

  (symbol (lib_id "antmicroCapacitors0402:C_10u_0402") (at 382.27 49.53 90) (unit 1)
    (in_bom yes) (on_board yes) (dnp no)
    (property "Reference" "C127" (at 382.905 45.085 90)
      (effects (font (size 1.524 1.524)) (justify right))
    )
    (property "Value" "C_10u_0402" (at 386.08 49.53 0)
      (effects (font (size 1.524 1.524)) hide)
    )
    (property "Footprint" "antmicro-footprints:C_0402_1005Metric" (at 377.19 44.45 0)
      (effects (font (size 1.524 1.524)) (justify left) hide)
    )
    (property "Datasheet" "https://www.yageo.com/en/Chart/Download/pdf/CC0402MRX5R5BB106" (at 382.27 49.53 0)
      (effects (font (size 1.27 1.27)) hide)
    )
    (property "Manufacturer" "YAGEO" (at 372.11 44.45 0)
      (effects (font (size 1.524 1.524)) (justify left) hide)
    )
    (property "MPN" "CC0402MRX5R5BB106" (at 374.65 44.45 0)
      (effects (font (size 1.524 1.524)) (justify left) hide)
    )
    (property "Val" "10u" (at 382.905 48.895 90)
      (effects (font (size 1.27 1.27)) (justify right))
    )
    (property "License" "Apache-2.0" (at 405.13 29.21 0)
      (effects (font (size 1.27 1.27) (thickness 0.15)) (justify left bottom) hide)
    )
    (property "Author" "Antmicro" (at 407.67 29.21 0)
      (effects (font (size 1.27 1.27) (thickness 0.15)) (justify left bottom) hide)
    )
    (property "Voltage" "" (at 410.21 29.21 0)
      (effects (font (size 1.27 1.27)) (justify left bottom) hide)
    )
    (property "Dielectric" "" (at 412.75 29.21 0)
      (effects (font (size 1.27 1.27)) (justify left bottom) hide)
    )
    (property "Public" "False" (at 415.29 29.21 0)
      (effects (font (size 1.27 1.27)) (justify left bottom) hide)
    )
    (pin "1")
    (pin "2")
    (instances
      (project "ecp5-dc-scm"
        (path ""
          (reference "C127") (unit 1)
        )
      )
    )
  )

  (symbol (lib_id "antmicroCapacitors0402:C_10u_0402") (at 389.89 49.53 90) (unit 1)
    (in_bom yes) (on_board yes) (dnp no)
    (property "Reference" "C132" (at 391.16 45.085 90)
      (effects (font (size 1.524 1.524)) (justify right))
    )
    (property "Value" "C_10u_0402" (at 393.7 49.53 0)
      (effects (font (size 1.524 1.524)) hide)
    )
    (property "Footprint" "antmicro-footprints:C_0402_1005Metric" (at 384.81 44.45 0)
      (effects (font (size 1.524 1.524)) (justify left) hide)
    )
    (property "Datasheet" "https://www.yageo.com/en/Chart/Download/pdf/CC0402MRX5R5BB106" (at 389.89 49.53 0)
      (effects (font (size 1.27 1.27)) hide)
    )
    (property "Manufacturer" "YAGEO" (at 379.73 44.45 0)
      (effects (font (size 1.524 1.524)) (justify left) hide)
    )
    (property "MPN" "CC0402MRX5R5BB106" (at 382.27 44.45 0)
      (effects (font (size 1.524 1.524)) (justify left) hide)
    )
    (property "Val" "10u" (at 391.16 48.895 90)
      (effects (font (size 1.27 1.27)) (justify right))
    )
    (property "License" "Apache-2.0" (at 412.75 29.21 0)
      (effects (font (size 1.27 1.27) (thickness 0.15)) (justify left bottom) hide)
    )
    (property "Author" "Antmicro" (at 415.29 29.21 0)
      (effects (font (size 1.27 1.27) (thickness 0.15)) (justify left bottom) hide)
    )
    (property "Voltage" "" (at 417.83 29.21 0)
      (effects (font (size 1.27 1.27)) (justify left bottom) hide)
    )
    (property "Dielectric" "" (at 420.37 29.21 0)
      (effects (font (size 1.27 1.27)) (justify left bottom) hide)
    )
    (property "Public" "False" (at 422.91 29.21 0)
      (effects (font (size 1.27 1.27)) (justify left bottom) hide)
    )
    (pin "1")
    (pin "2")
    (instances
      (project "ecp5-dc-scm"
        (path ""
          (reference "C132") (unit 1)
        )
      )
    )
  )

  (symbol (lib_id "antmicroResistors0402:R_10k_0402") (at 238.76 261.62 90) (mirror x) (unit 1)
    (in_bom yes) (on_board yes) (dnp no)
    (property "Reference" "R104" (at 236.22 262.89 90)
      (effects (font (size 1.524 1.524)) (justify left))
    )
    (property "Value" "R_10k_0402" (at 242.57 261.62 0)
      (effects (font (size 1.524 1.524)) hide)
    )
    (property "Footprint" "antmicro-footprints:R_0402_1005Metric" (at 233.68 266.7 0)
      (effects (font (size 1.524 1.524)) (justify left) hide)
    )
    (property "Datasheet" "https://www.bourns.com/docs/product-datasheets/cr.pdf" (at 238.76 261.62 0)
      (effects (font (size 1.27 1.27)) hide)
    )
    (property "Manufacturer" "Bourns" (at 228.6 266.7 0)
      (effects (font (size 1.524 1.524)) (justify left) hide)
    )
    (property "MPN" "CR0402-FX-1002GLF" (at 231.14 266.7 0)
      (effects (font (size 1.524 1.524)) (justify left) hide)
    )
    (property "Val" "10k" (at 236.22 265.43 90)
      (effects (font (size 1.27 1.27)) (justify left))
    )
    (property "License" "Apache-2.0" (at 264.16 281.94 0)
      (effects (font (size 1.27 1.27) (thickness 0.15)) (justify left bottom) hide)
    )
    (property "Author" "Antmicro" (at 266.7 281.94 0)
      (effects (font (size 1.27 1.27) (thickness 0.15)) (justify left bottom) hide)
    )
    (property "Tolerance" "1%" (at 248.92 281.94 0)
      (effects (font (size 1.27 1.27)) (justify left bottom) hide)
    )
    (property "Public" "False" (at 269.24 281.94 0)
      (effects (font (size 1.27 1.27)) (justify left bottom) hide)
    )
    (pin "1")
    (pin "2")
    (instances
      (project "ecp5-dc-scm"
        (path ""
          (reference "R104") (unit 1)
        )
      )
    )
  )

  (symbol (lib_id "antmicroResistors0402:R_1k_0402") (at 257.81 256.54 0) (unit 1)
    (in_bom yes) (on_board yes) (dnp no)
    (property "Reference" "R111" (at 260.35 254 0)
      (effects (font (size 1.524 1.524)))
    )
    (property "Value" "R_1k_0402" (at 257.81 260.35 0)
      (effects (font (size 1.524 1.524)) hide)
    )
    (property "Footprint" "antmicro-footprints:R_0402_1005Metric" (at 262.89 251.46 0)
      (effects (font (size 1.524 1.524)) (justify left) hide)
    )
    (property "Datasheet" "https://www.bourns.com/docs/product-datasheets/cr.pdf" (at 257.81 256.54 0)
      (effects (font (size 1.27 1.27)) hide)
    )
    (property "Manufacturer" "Bourns" (at 262.89 246.38 0)
      (effects (font (size 1.524 1.524)) (justify left) hide)
    )
    (property "MPN" "CR0402-FX-1001GLF" (at 262.89 248.92 0)
      (effects (font (size 1.524 1.524)) (justify left) hide)
    )
    (property "Val" "1k" (at 260.35 259.08 0)
      (effects (font (size 1.27 1.27)))
    )
    (property "License" "Apache-2.0" (at 278.13 281.94 0)
      (effects (font (size 1.27 1.27) (thickness 0.15)) (justify left bottom) hide)
    )
    (property "Author" "Antmicro" (at 278.13 284.48 0)
      (effects (font (size 1.27 1.27) (thickness 0.15)) (justify left bottom) hide)
    )
    (property "Tolerance" "1%" (at 278.13 266.7 0)
      (effects (font (size 1.27 1.27)) (justify left bottom) hide)
    )
    (property "Public" "False" (at 278.13 287.02 0)
      (effects (font (size 1.27 1.27)) (justify left bottom) hide)
    )
    (pin "1")
    (pin "2")
    (instances
      (project "ecp5-dc-scm"
        (path ""
          (reference "R111") (unit 1)
        )
      )
    )
  )

  (symbol (lib_id "antmicroTransistorsFETsMOSFETsSingle:2N7002_SOT-23-3") (at 246.38 273.05 0) (unit 1)
    (in_bom yes) (on_board yes) (dnp no) (fields_autoplaced)
    (property "Reference" "Q14" (at 257.175 269.24 0)
      (effects (font (size 1.524 1.524)) (justify left))
    )
    (property "Value" "2N7002" (at 257.175 271.78 0)
      (effects (font (size 1.524 1.524)) (justify left))
    )
    (property "Footprint" "antmicro-footprints:SOT-23-3" (at 251.46 267.97 0)
      (effects (font (size 1.524 1.524)) (justify left) hide)
    )
    (property "Datasheet" "https://www.onsemi.com/pub/Collateral/NDS7002A-D.PDF" (at 251.46 265.43 0)
      (effects (font (size 1.524 1.524)) (justify left) hide)
    )
    (property "MPN" "2N7002" (at 251.46 260.35 0)
      (effects (font (size 1.524 1.524)) (justify left) hide)
    )
    (property "Manufacturer" "ON Semiconductor" (at 251.46 245.11 0)
      (effects (font (size 1.524 1.524)) (justify left) hide)
    )
    (property "Author" "Antmicro" (at 269.24 293.37 0)
      (effects (font (size 1.27 1.27) (thickness 0.15)) (justify left bottom) hide)
    )
    (property "License" "Apache-2.0" (at 269.24 295.91 0)
      (effects (font (size 1.27 1.27) (thickness 0.15)) (justify left bottom) hide)
    )
    (pin "1")
    (pin "2")
    (pin "3")
    (instances
      (project "ecp5-dc-scm"
        (path ""
          (reference "Q14") (unit 1)
        )
      )
    )
  )

  (symbol (lib_id "antmicropower:GND") (at 73.66 139.7 0) (unit 1)
    (in_bom yes) (on_board yes) (dnp no)
    (property "Reference" "#PWR062" (at 73.66 146.05 0)
      (effects (font (size 1.27 1.27)) hide)
    )
    (property "Value" "GND" (at 73.787 144.0942 0)
      (effects (font (size 1.27 1.27)))
    )
    (property "Footprint" "" (at 73.66 139.7 0)
      (effects (font (size 1.27 1.27)) hide)
    )
    (property "Datasheet" "" (at 73.66 139.7 0)
      (effects (font (size 1.27 1.27)) hide)
    )
    (property "Author" "Antmicro" (at 82.55 147.32 0)
      (effects (font (size 1.27 1.27) (thickness 0.15)) (justify left bottom) hide)
    )
    (property "License" "Apache-2.0" (at 82.55 149.86 0)
      (effects (font (size 1.27 1.27) (thickness 0.15)) (justify left bottom) hide)
    )
    (pin "1")
    (instances
      (project "ecp5-dc-scm"
        (path ""
          (reference "#PWR062") (unit 1)
        )
      )
    )
  )

  (symbol (lib_id "antmicropower:GND") (at 119.38 152.4 0) (unit 1)
    (in_bom yes) (on_board yes) (dnp no)
    (property "Reference" "#PWR068" (at 119.38 158.75 0)
      (effects (font (size 1.27 1.27)) hide)
    )
    (property "Value" "GND" (at 119.507 156.7942 0)
      (effects (font (size 1.27 1.27)))
    )
    (property "Footprint" "" (at 119.38 152.4 0)
      (effects (font (size 1.27 1.27)) hide)
    )
    (property "Datasheet" "" (at 119.38 152.4 0)
      (effects (font (size 1.27 1.27)) hide)
    )
    (property "Author" "Antmicro" (at 128.27 160.02 0)
      (effects (font (size 1.27 1.27) (thickness 0.15)) (justify left bottom) hide)
    )
    (property "License" "Apache-2.0" (at 128.27 162.56 0)
      (effects (font (size 1.27 1.27) (thickness 0.15)) (justify left bottom) hide)
    )
    (pin "1")
    (instances
      (project "ecp5-dc-scm"
        (path ""
          (reference "#PWR068") (unit 1)
        )
      )
    )
  )

  (symbol (lib_id "antmicropower:GND") (at 198.12 153.67 0) (unit 1)
    (in_bom yes) (on_board yes) (dnp no)
    (property "Reference" "#PWR074" (at 198.12 160.02 0)
      (effects (font (size 1.27 1.27)) hide)
    )
    (property "Value" "GND" (at 198.247 158.0642 0)
      (effects (font (size 1.27 1.27)))
    )
    (property "Footprint" "" (at 198.12 153.67 0)
      (effects (font (size 1.27 1.27)) hide)
    )
    (property "Datasheet" "" (at 198.12 153.67 0)
      (effects (font (size 1.27 1.27)) hide)
    )
    (property "Author" "Antmicro" (at 207.01 161.29 0)
      (effects (font (size 1.27 1.27) (thickness 0.15)) (justify left bottom) hide)
    )
    (property "License" "Apache-2.0" (at 207.01 163.83 0)
      (effects (font (size 1.27 1.27) (thickness 0.15)) (justify left bottom) hide)
    )
    (pin "1")
    (instances
      (project "ecp5-dc-scm"
        (path ""
          (reference "#PWR074") (unit 1)
        )
      )
    )
  )

  (symbol (lib_id "antmicropower:GND") (at 254 208.28 0) (unit 1)
    (in_bom yes) (on_board yes) (dnp no)
    (property "Reference" "#PWR077" (at 254 214.63 0)
      (effects (font (size 1.27 1.27)) hide)
    )
    (property "Value" "GND" (at 254.127 212.6742 0)
      (effects (font (size 1.27 1.27)))
    )
    (property "Footprint" "" (at 254 208.28 0)
      (effects (font (size 1.27 1.27)) hide)
    )
    (property "Datasheet" "" (at 254 208.28 0)
      (effects (font (size 1.27 1.27)) hide)
    )
    (property "Author" "Antmicro" (at 262.89 215.9 0)
      (effects (font (size 1.27 1.27) (thickness 0.15)) (justify left bottom) hide)
    )
    (property "License" "Apache-2.0" (at 262.89 218.44 0)
      (effects (font (size 1.27 1.27) (thickness 0.15)) (justify left bottom) hide)
    )
    (pin "1")
    (instances
      (project "ecp5-dc-scm"
        (path ""
          (reference "#PWR077") (unit 1)
        )
      )
    )
  )

  (symbol (lib_id "antmicroResistors0402:R_10k_0402") (at 238.76 190.5 270) (unit 1)
    (in_bom yes) (on_board yes) (dnp no)
    (property "Reference" "R101" (at 239.395 186.69 90)
      (effects (font (size 1.524 1.524)) (justify left))
    )
    (property "Value" "R_10k_0402" (at 234.95 190.5 0)
      (effects (font (size 1.524 1.524)) hide)
    )
    (property "Footprint" "antmicro-footprints:R_0402_1005Metric" (at 243.84 195.58 0)
      (effects (font (size 1.524 1.524)) (justify left) hide)
    )
    (property "Datasheet" "https://www.bourns.com/docs/product-datasheets/cr.pdf" (at 238.76 190.5 0)
      (effects (font (size 1.27 1.27)) hide)
    )
    (property "Manufacturer" "Bourns" (at 248.92 195.58 0)
      (effects (font (size 1.524 1.524)) (justify left) hide)
    )
    (property "MPN" "CR0402-FX-1002GLF" (at 246.38 195.58 0)
      (effects (font (size 1.524 1.524)) (justify left) hide)
    )
    (property "Val" "10k" (at 240.03 193.675 90)
      (effects (font (size 1.27 1.27)) (justify left))
    )
    (property "License" "Apache-2.0" (at 213.36 210.82 0)
      (effects (font (size 1.27 1.27) (thickness 0.15)) (justify left bottom) hide)
    )
    (property "Author" "Antmicro" (at 210.82 210.82 0)
      (effects (font (size 1.27 1.27) (thickness 0.15)) (justify left bottom) hide)
    )
    (property "Tolerance" "1%" (at 228.6 210.82 0)
      (effects (font (size 1.27 1.27)) (justify left bottom) hide)
    )
    (property "Public" "False" (at 208.28 210.82 0)
      (effects (font (size 1.27 1.27)) (justify left bottom) hide)
    )
    (pin "1")
    (pin "2")
    (instances
      (project "ecp5-dc-scm"
        (path ""
          (reference "R101") (unit 1)
        )
      )
    )
  )

  (symbol (lib_id "antmicroResistors0402:R_1k_0402") (at 257.81 185.42 0) (unit 1)
    (in_bom yes) (on_board yes) (dnp no)
    (property "Reference" "R107" (at 260.985 182.88 0)
      (effects (font (size 1.524 1.524)))
    )
    (property "Value" "R_1k_0402" (at 257.81 189.23 0)
      (effects (font (size 1.524 1.524)) hide)
    )
    (property "Footprint" "antmicro-footprints:R_0402_1005Metric" (at 262.89 180.34 0)
      (effects (font (size 1.524 1.524)) (justify left) hide)
    )
    (property "Datasheet" "https://www.bourns.com/docs/product-datasheets/cr.pdf" (at 257.81 185.42 0)
      (effects (font (size 1.27 1.27)) hide)
    )
    (property "Manufacturer" "Bourns" (at 262.89 175.26 0)
      (effects (font (size 1.524 1.524)) (justify left) hide)
    )
    (property "MPN" "CR0402-FX-1001GLF" (at 262.89 177.8 0)
      (effects (font (size 1.524 1.524)) (justify left) hide)
    )
    (property "Val" "1k" (at 260.35 187.96 0)
      (effects (font (size 1.27 1.27)))
    )
    (property "License" "Apache-2.0" (at 278.13 210.82 0)
      (effects (font (size 1.27 1.27) (thickness 0.15)) (justify left bottom) hide)
    )
    (property "Author" "Antmicro" (at 278.13 213.36 0)
      (effects (font (size 1.27 1.27) (thickness 0.15)) (justify left bottom) hide)
    )
    (property "Tolerance" "1%" (at 278.13 195.58 0)
      (effects (font (size 1.27 1.27)) (justify left bottom) hide)
    )
    (property "Public" "False" (at 278.13 215.9 0)
      (effects (font (size 1.27 1.27)) (justify left bottom) hide)
    )
    (pin "1")
    (pin "2")
    (instances
      (project "ecp5-dc-scm"
        (path ""
          (reference "R107") (unit 1)
        )
      )
    )
  )

  (symbol (lib_id "antmicroTransistorsFETsMOSFETsSingle:2N7002_SOT-23-3") (at 246.38 201.93 0) (unit 1)
    (in_bom yes) (on_board yes) (dnp no) (fields_autoplaced)
    (property "Reference" "Q10" (at 257.81 198.12 0)
      (effects (font (size 1.524 1.524)) (justify left))
    )
    (property "Value" "2N7002" (at 257.81 200.66 0)
      (effects (font (size 1.524 1.524)) (justify left))
    )
    (property "Footprint" "antmicro-footprints:SOT-23-3" (at 251.46 196.85 0)
      (effects (font (size 1.524 1.524)) (justify left) hide)
    )
    (property "Datasheet" "https://www.onsemi.com/pub/Collateral/NDS7002A-D.PDF" (at 251.46 194.31 0)
      (effects (font (size 1.524 1.524)) (justify left) hide)
    )
    (property "MPN" "2N7002" (at 251.46 189.23 0)
      (effects (font (size 1.524 1.524)) (justify left) hide)
    )
    (property "Manufacturer" "ON Semiconductor" (at 251.46 173.99 0)
      (effects (font (size 1.524 1.524)) (justify left) hide)
    )
    (property "Author" "Antmicro" (at 269.24 222.25 0)
      (effects (font (size 1.27 1.27) (thickness 0.15)) (justify left bottom) hide)
    )
    (property "License" "Apache-2.0" (at 269.24 224.79 0)
      (effects (font (size 1.27 1.27) (thickness 0.15)) (justify left bottom) hide)
    )
    (pin "1")
    (pin "2")
    (pin "3")
    (instances
      (project "ecp5-dc-scm"
        (path ""
          (reference "Q10") (unit 1)
        )
      )
    )
  )

  (symbol (lib_id "antmicroResistors0603:R_10R_0603") (at 90.17 127 0) (unit 1)
    (in_bom yes) (on_board yes) (dnp no)
    (property "Reference" "R88" (at 88.9 124.46 0)
      (effects (font (size 1.524 1.524)))
    )
    (property "Value" "R_10R_0603" (at 90.17 130.81 0)
      (effects (font (size 1.524 1.524)) hide)
    )
    (property "Footprint" "antmicro-footprints:R_0603_1608Metric" (at 95.25 121.92 0)
      (effects (font (size 1.524 1.524)) (justify left) hide)
    )
    (property "Datasheet" "https://www.bourns.com/docs/product-datasheets/cr.pdf" (at 90.17 127 0)
      (effects (font (size 1.27 1.27)) hide)
    )
    (property "Manufacturer" "Bourns" (at 95.25 116.84 0)
      (effects (font (size 1.524 1.524)) (justify left) hide)
    )
    (property "MPN" "CR0603-FX-10R0ELF" (at 95.25 119.38 0)
      (effects (font (size 1.524 1.524)) (justify left) hide)
    )
    (property "Val" "10R" (at 90.805 128.905 0)
      (effects (font (size 1.27 1.27)))
    )
    (property "License" "Apache-2.0" (at 110.49 152.4 0)
      (effects (font (size 1.27 1.27) (thickness 0.15)) (justify left bottom) hide)
    )
    (property "Author" "Antmicro" (at 110.49 154.94 0)
      (effects (font (size 1.27 1.27) (thickness 0.15)) (justify left bottom) hide)
    )
    (property "Tolerance" "1%" (at 110.49 137.16 0)
      (effects (font (size 1.27 1.27)) (justify left bottom) hide)
    )
    (property "Public" "False" (at 110.49 157.48 0)
      (effects (font (size 1.27 1.27)) (justify left bottom) hide)
    )
    (pin "1")
    (pin "2")
    (instances
      (project "ecp5-dc-scm"
        (path ""
          (reference "R88") (unit 1)
        )
      )
    )
  )

  (symbol (lib_id "antmicroCapacitors0402:C_100n_0402") (at 99.06 135.89 90) (unit 1)
    (in_bom yes) (on_board yes) (dnp no) (fields_autoplaced)
    (property "Reference" "C100" (at 101.6 132.0736 90)
      (effects (font (size 1.524 1.524)) (justify right))
    )
    (property "Value" "C_100n_0402" (at 102.87 135.89 0)
      (effects (font (size 1.524 1.524)) hide)
    )
    (property "Footprint" "antmicro-footprints:C_0402_1005Metric" (at 93.98 130.81 0)
      (effects (font (size 1.524 1.524)) (justify left) hide)
    )
    (property "Datasheet" "https://www.murata.com/products/productdetail?partno=GRM155R61H104KE14%23" (at 99.06 135.89 0)
      (effects (font (size 1.27 1.27)) hide)
    )
    (property "Manufacturer" "Murata" (at 88.9 130.81 0)
      (effects (font (size 1.524 1.524)) (justify left) hide)
    )
    (property "MPN" "GRM155R61H104KE14D" (at 91.44 130.81 0)
      (effects (font (size 1.524 1.524)) (justify left) hide)
    )
    (property "Val" "100n" (at 101.6 134.6136 90)
      (effects (font (size 1.27 1.27)) (justify right))
    )
    (property "License" "Apache-2.0" (at 121.92 115.57 0)
      (effects (font (size 1.27 1.27) (thickness 0.15)) (justify left bottom) hide)
    )
    (property "Author" "Antmicro" (at 124.46 115.57 0)
      (effects (font (size 1.27 1.27) (thickness 0.15)) (justify left bottom) hide)
    )
    (property "Voltage" "50V" (at 127 115.57 0)
      (effects (font (size 1.27 1.27)) (justify left bottom) hide)
    )
    (property "Dielectric" "X5R" (at 129.54 115.57 0)
      (effects (font (size 1.27 1.27)) (justify left bottom) hide)
    )
    (property "Public" "False" (at 132.08 115.57 0)
      (effects (font (size 1.27 1.27)) (justify left bottom) hide)
    )
    (pin "1")
    (pin "2")
    (instances
      (project "ecp5-dc-scm"
        (path ""
          (reference "C100") (unit 1)
        )
      )
    )
  )

  (symbol (lib_id "antmicroResistors0402:R_47k_0402") (at 116.84 138.43 270) (unit 1)
    (in_bom yes) (on_board yes) (dnp no) (fields_autoplaced)
    (property "Reference" "R89" (at 114.935 139.7 90)
      (effects (font (size 1.524 1.524)) (justify right))
    )
    (property "Value" "R_47k_0402" (at 113.03 138.43 0)
      (effects (font (size 1.524 1.524)) hide)
    )
    (property "Footprint" "antmicro-footprints:R_0402_1005Metric" (at 121.92 143.51 0)
      (effects (font (size 1.524 1.524)) (justify left) hide)
    )
    (property "Datasheet" "https://www.bourns.com/docs/product-datasheets/cr.pdf" (at 116.84 138.43 0)
      (effects (font (size 1.27 1.27)) hide)
    )
    (property "Manufacturer" "Bourns" (at 127 143.51 0)
      (effects (font (size 1.524 1.524)) (justify left) hide)
    )
    (property "MPN" "CR0402-FX-4702GLF" (at 124.46 143.51 0)
      (effects (font (size 1.524 1.524)) (justify left) hide)
    )
    (property "Val" "47k" (at 114.935 142.24 90)
      (effects (font (size 1.27 1.27)) (justify right))
    )
    (property "License" "Apache-2.0" (at 91.44 158.75 0)
      (effects (font (size 1.27 1.27) (thickness 0.15)) (justify left bottom) hide)
    )
    (property "Author" "Antmicro" (at 88.9 158.75 0)
      (effects (font (size 1.27 1.27) (thickness 0.15)) (justify left bottom) hide)
    )
    (property "Tolerance" "1%" (at 106.68 158.75 0)
      (effects (font (size 1.27 1.27)) (justify left bottom) hide)
    )
    (property "Public" "False" (at 86.36 158.75 0)
      (effects (font (size 1.27 1.27)) (justify left bottom) hide)
    )
    (pin "1")
    (pin "2")
    (instances
      (project "ecp5-dc-scm"
        (path ""
          (reference "R89") (unit 1)
        )
      )
    )
  )

  (symbol (lib_id "antmicroCapacitors0402:C_1n8_0402") (at 161.29 142.24 0) (unit 1)
    (in_bom yes) (on_board yes) (dnp no) (fields_autoplaced)
    (property "Reference" "C106" (at 163.8363 135.89 0)
      (effects (font (size 1.524 1.524)))
    )
    (property "Value" "C_1n8_0402" (at 161.29 146.05 0)
      (effects (font (size 1.524 1.524)) hide)
    )
    (property "Footprint" "antmicro-footprints:C_0402_1005Metric" (at 166.37 137.16 0)
      (effects (font (size 1.524 1.524)) (justify left) hide)
    )
    (property "Datasheet" "https://www.passivecomponent.com/wp-content/uploads/datasheet/WTC_MLCC_General_Purpose.pdf" (at 161.29 142.24 0)
      (effects (font (size 1.27 1.27)) hide)
    )
    (property "Manufacturer" "Walsin" (at 166.37 132.08 0)
      (effects (font (size 1.524 1.524)) (justify left) hide)
    )
    (property "MPN" "0402B182K500CT" (at 166.37 134.62 0)
      (effects (font (size 1.524 1.524)) (justify left) hide)
    )
    (property "Val" "1n8" (at 163.8363 138.43 0)
      (effects (font (size 1.27 1.27)))
    )
    (property "License" "Apache-2.0" (at 181.61 165.1 0)
      (effects (font (size 1.27 1.27) (thickness 0.15)) (justify left bottom) hide)
    )
    (property "Author" "Antmicro" (at 181.61 167.64 0)
      (effects (font (size 1.27 1.27) (thickness 0.15)) (justify left bottom) hide)
    )
    (property "Voltage" "" (at 181.61 170.18 0)
      (effects (font (size 1.27 1.27)) (justify left bottom) hide)
    )
    (property "Dielectric" "" (at 181.61 172.72 0)
      (effects (font (size 1.27 1.27)) (justify left bottom) hide)
    )
    (property "Public" "False" (at 181.61 175.26 0)
      (effects (font (size 1.27 1.27)) (justify left bottom) hide)
    )
    (pin "1")
    (pin "2")
    (instances
      (project "ecp5-dc-scm"
        (path ""
          (reference "C106") (unit 1)
        )
      )
    )
  )

  (symbol (lib_id "antmicroResistors0402:R_4k7_0402") (at 171.45 142.24 0) (unit 1)
    (in_bom yes) (on_board yes) (dnp no) (fields_autoplaced)
    (property "Reference" "R93" (at 173.99 135.89 0)
      (effects (font (size 1.524 1.524)))
    )
    (property "Value" "R_4k7_0402" (at 171.45 146.05 0)
      (effects (font (size 1.524 1.524)) hide)
    )
    (property "Footprint" "antmicro-footprints:R_0402_1005Metric" (at 176.53 137.16 0)
      (effects (font (size 1.524 1.524)) (justify left) hide)
    )
    (property "Datasheet" "https://www.bourns.com/docs/product-datasheets/cr.pdf" (at 171.45 142.24 0)
      (effects (font (size 1.27 1.27)) hide)
    )
    (property "Manufacturer" "Bourns" (at 176.53 132.08 0)
      (effects (font (size 1.524 1.524)) (justify left) hide)
    )
    (property "MPN" "CR0402-FX-4701GLF" (at 176.53 134.62 0)
      (effects (font (size 1.524 1.524)) (justify left) hide)
    )
    (property "Val" "4k7" (at 173.99 138.43 0)
      (effects (font (size 1.27 1.27)))
    )
    (property "License" "Apache-2.0" (at 191.77 167.64 0)
      (effects (font (size 1.27 1.27) (thickness 0.15)) (justify left bottom) hide)
    )
    (property "Author" "Antmicro" (at 191.77 170.18 0)
      (effects (font (size 1.27 1.27) (thickness 0.15)) (justify left bottom) hide)
    )
    (property "Tolerance" "1%" (at 191.77 152.4 0)
      (effects (font (size 1.27 1.27)) (justify left bottom) hide)
    )
    (property "Public" "False" (at 191.77 172.72 0)
      (effects (font (size 1.27 1.27)) (justify left bottom) hide)
    )
    (pin "1")
    (pin "2")
    (instances
      (project "ecp5-dc-scm"
        (path ""
          (reference "R93") (unit 1)
        )
      )
    )
  )

  (symbol (lib_id "antmicroCapacitors0402:C_180p_0402") (at 161.29 147.32 0) (unit 1)
    (in_bom yes) (on_board yes) (dnp no) (fields_autoplaced)
    (property "Reference" "C107" (at 163.8363 151.13 0)
      (effects (font (size 1.524 1.524)))
    )
    (property "Value" "C_180p_0402" (at 161.29 151.13 0)
      (effects (font (size 1.524 1.524)) hide)
    )
    (property "Footprint" "antmicro-footprints:C_0402_1005Metric" (at 166.37 142.24 0)
      (effects (font (size 1.524 1.524)) (justify left) hide)
    )
    (property "Datasheet" "https://spicat.kyocera-avx.com/product/mlcc/chartview/04025A181JAT2A/" (at 161.29 147.32 0)
      (effects (font (size 1.27 1.27)) hide)
    )
    (property "Manufacturer" "AVX" (at 166.37 137.16 0)
      (effects (font (size 1.524 1.524)) (justify left) hide)
    )
    (property "MPN" "04025A181JAT2A" (at 166.37 139.7 0)
      (effects (font (size 1.524 1.524)) (justify left) hide)
    )
    (property "Val" "180p" (at 163.8363 153.67 0)
      (effects (font (size 1.27 1.27)))
    )
    (property "License" "Apache-2.0" (at 181.61 170.18 0)
      (effects (font (size 1.27 1.27) (thickness 0.15)) (justify left bottom) hide)
    )
    (property "Author" "Antmicro" (at 181.61 172.72 0)
      (effects (font (size 1.27 1.27) (thickness 0.15)) (justify left bottom) hide)
    )
    (property "Voltage" "" (at 181.61 175.26 0)
      (effects (font (size 1.27 1.27)) (justify left bottom) hide)
    )
    (property "Dielectric" "" (at 181.61 177.8 0)
      (effects (font (size 1.27 1.27)) (justify left bottom) hide)
    )
    (property "Public" "False" (at 181.61 180.34 0)
      (effects (font (size 1.27 1.27)) (justify left bottom) hide)
    )
    (pin "1")
    (pin "2")
    (instances
      (project "ecp5-dc-scm"
        (path ""
          (reference "C107") (unit 1)
        )
      )
    )
  )

  (symbol (lib_id "antmicroResistors0402:R_10k_0402") (at 180.34 128.27 270) (unit 1)
    (in_bom yes) (on_board yes) (dnp no) (fields_autoplaced)
    (property "Reference" "R98" (at 177.8 129.54 90)
      (effects (font (size 1.524 1.524)) (justify right))
    )
    (property "Value" "R_10k_0402" (at 176.53 128.27 0)
      (effects (font (size 1.524 1.524)) hide)
    )
    (property "Footprint" "antmicro-footprints:R_0402_1005Metric" (at 185.42 133.35 0)
      (effects (font (size 1.524 1.524)) (justify left) hide)
    )
    (property "Datasheet" "https://www.bourns.com/docs/product-datasheets/cr.pdf" (at 180.34 128.27 0)
      (effects (font (size 1.27 1.27)) hide)
    )
    (property "Manufacturer" "Bourns" (at 190.5 133.35 0)
      (effects (font (size 1.524 1.524)) (justify left) hide)
    )
    (property "MPN" "CR0402-FX-1002GLF" (at 187.96 133.35 0)
      (effects (font (size 1.524 1.524)) (justify left) hide)
    )
    (property "Val" "10k" (at 177.8 132.08 90)
      (effects (font (size 1.27 1.27)) (justify right))
    )
    (property "License" "Apache-2.0" (at 154.94 148.59 0)
      (effects (font (size 1.27 1.27) (thickness 0.15)) (justify left bottom) hide)
    )
    (property "Author" "Antmicro" (at 152.4 148.59 0)
      (effects (font (size 1.27 1.27) (thickness 0.15)) (justify left bottom) hide)
    )
    (property "Tolerance" "1%" (at 170.18 148.59 0)
      (effects (font (size 1.27 1.27)) (justify left bottom) hide)
    )
    (property "Public" "False" (at 149.86 148.59 0)
      (effects (font (size 1.27 1.27)) (justify left bottom) hide)
    )
    (pin "1")
    (pin "2")
    (instances
      (project "ecp5-dc-scm"
        (path ""
          (reference "R98") (unit 1)
        )
      )
    )
  )

  (symbol (lib_id "antmicroCapacitors0402:C_750p_0402") (at 187.96 134.62 90) (unit 1)
    (in_bom yes) (on_board yes) (dnp no) (fields_autoplaced)
    (property "Reference" "C108" (at 190.5 130.8036 90)
      (effects (font (size 1.524 1.524)) (justify right))
    )
    (property "Value" "C_750p_0402" (at 191.77 134.62 0)
      (effects (font (size 1.524 1.524)) hide)
    )
    (property "Footprint" "antmicro-footprints:C_0402_1005Metric" (at 182.88 129.54 0)
      (effects (font (size 1.524 1.524)) (justify left) hide)
    )
    (property "Datasheet" "https://www.kemet.com/en/us/capacitors/product/C0402C751J5GACTU.html" (at 187.96 134.62 0)
      (effects (font (size 1.27 1.27)) hide)
    )
    (property "Manufacturer" "KEMET" (at 177.8 129.54 0)
      (effects (font (size 1.524 1.524)) (justify left) hide)
    )
    (property "MPN" "C0402C751J5GACTU" (at 180.34 129.54 0)
      (effects (font (size 1.524 1.524)) (justify left) hide)
    )
    (property "Val" "750p" (at 190.5 133.3436 90)
      (effects (font (size 1.27 1.27)) (justify right))
    )
    (property "License" "Apache-2.0" (at 210.82 114.3 0)
      (effects (font (size 1.27 1.27) (thickness 0.15)) (justify left bottom) hide)
    )
    (property "Author" "Antmicro" (at 213.36 114.3 0)
      (effects (font (size 1.27 1.27) (thickness 0.15)) (justify left bottom) hide)
    )
    (property "Voltage" "" (at 215.9 114.3 0)
      (effects (font (size 1.27 1.27)) (justify left bottom) hide)
    )
    (property "Dielectric" "" (at 218.44 114.3 0)
      (effects (font (size 1.27 1.27)) (justify left bottom) hide)
    )
    (property "Public" "False" (at 220.98 114.3 0)
      (effects (font (size 1.27 1.27)) (justify left bottom) hide)
    )
    (pin "1")
    (pin "2")
    (instances
      (project "ecp5-dc-scm"
        (path ""
          (reference "C108") (unit 1)
        )
      )
    )
  )

  (symbol (lib_id "antmicroFixedInductors:L_800n_13A_Coilcraft-XAL5030") (at 149.86 127 0) (unit 1)
    (in_bom yes) (on_board yes) (dnp no)
    (property "Reference" "L1" (at 152.4 125.095 0)
      (effects (font (size 1.524 1.524)))
    )
    (property "Value" "XAL5030-801" (at 149.86 124.2568 0)
      (effects (font (size 1.524 1.524)) hide)
    )
    (property "Footprint" "antmicro-footprints:L_Coilcraft-XAL5030" (at 170.18 120.65 0)
      (effects (font (size 1.524 1.524)) hide)
    )
    (property "Datasheet" "https://eu.mouser.com/datasheet/2/597/xal50xx-270657.pdf" (at 149.86 127 0)
      (effects (font (size 1.524 1.524)) hide)
    )
    (property "Manufacturer" "Coilcraft" (at 152.4 115.57 0)
      (effects (font (size 1.27 1.27)) hide)
    )
    (property "MPN" "XAL5030-801MEC" (at 156.21 118.11 0)
      (effects (font (size 1.27 1.27)) hide)
    )
    (property "Val" "800n/13A" (at 147.32 129.54 0)
      (effects (font (size 1.27 1.27) (thickness 0.15)) (justify left bottom))
    )
    (property "ISat" "18.5 A" (at 163.83 143.51 0)
      (effects (font (size 1.27 1.27)) (justify left) hide)
    )
    (property "IMax" "13 A" (at 163.83 147.32 0)
      (effects (font (size 1.27 1.27) (thickness 0.15)) (justify left bottom) hide)
    )
    (property "Size" "5.28x5.48" (at 163.83 149.86 0)
      (effects (font (size 1.27 1.27) (thickness 0.15)) (justify left bottom) hide)
    )
    (property "Author" "Antmicro" (at 163.83 152.4 0)
      (effects (font (size 1.27 1.27) (thickness 0.15)) (justify left bottom) hide)
    )
    (property "License" "Apache-2.0" (at 163.83 154.94 0)
      (effects (font (size 1.27 1.27) (thickness 0.15)) (justify left bottom) hide)
    )
    (property "Public" "False" (at 163.83 157.48 0)
      (effects (font (size 1.27 1.27)) (justify left bottom) hide)
    )
    (pin "1")
    (pin "2")
    (instances
      (project "ecp5-dc-scm"
        (path ""
          (reference "L1") (unit 1)
        )
      )
    )
  )

  (symbol (lib_id "antmicroTransistorsFETsMOSFETsSingle:2N7002_SOT-23-3") (at 246.38 86.36 0) (unit 1)
    (in_bom yes) (on_board yes) (dnp no) (fields_autoplaced)
    (property "Reference" "Q16" (at 257.81 82.55 0)
      (effects (font (size 1.524 1.524)) (justify left))
    )
    (property "Value" "2N7002" (at 257.81 85.09 0)
      (effects (font (size 1.524 1.524)) (justify left))
    )
    (property "Footprint" "antmicro-footprints:SOT-23-3" (at 251.46 81.28 0)
      (effects (font (size 1.524 1.524)) (justify left) hide)
    )
    (property "Datasheet" "https://www.onsemi.com/pub/Collateral/NDS7002A-D.PDF" (at 251.46 78.74 0)
      (effects (font (size 1.524 1.524)) (justify left) hide)
    )
    (property "MPN" "2N7002" (at 251.46 73.66 0)
      (effects (font (size 1.524 1.524)) (justify left) hide)
    )
    (property "Manufacturer" "ON Semiconductor" (at 251.46 58.42 0)
      (effects (font (size 1.524 1.524)) (justify left) hide)
    )
    (property "Author" "Antmicro" (at 269.24 106.68 0)
      (effects (font (size 1.27 1.27) (thickness 0.15)) (justify left bottom) hide)
    )
    (property "License" "Apache-2.0" (at 269.24 109.22 0)
      (effects (font (size 1.27 1.27) (thickness 0.15)) (justify left bottom) hide)
    )
    (pin "1")
    (pin "2")
    (pin "3")
    (instances
      (project "ecp5-dc-scm"
        (path ""
          (reference "Q16") (unit 1)
        )
      )
    )
  )

  (symbol (lib_id "antmicroResistors0402:R_1k_0402") (at 257.81 69.85 0) (unit 1)
    (in_bom yes) (on_board yes) (dnp no) (fields_autoplaced)
    (property "Reference" "R113" (at 260.35 73.66 0)
      (effects (font (size 1.524 1.524)))
    )
    (property "Value" "R_1k_0402" (at 257.81 73.66 0)
      (effects (font (size 1.524 1.524)) hide)
    )
    (property "Footprint" "antmicro-footprints:R_0402_1005Metric" (at 262.89 64.77 0)
      (effects (font (size 1.524 1.524)) (justify left) hide)
    )
    (property "Datasheet" "https://www.bourns.com/docs/product-datasheets/cr.pdf" (at 257.81 69.85 0)
      (effects (font (size 1.27 1.27)) hide)
    )
    (property "Manufacturer" "Bourns" (at 262.89 59.69 0)
      (effects (font (size 1.524 1.524)) (justify left) hide)
    )
    (property "MPN" "CR0402-FX-1001GLF" (at 262.89 62.23 0)
      (effects (font (size 1.524 1.524)) (justify left) hide)
    )
    (property "Val" "1k" (at 260.35 76.2 0)
      (effects (font (size 1.27 1.27)))
    )
    (property "License" "Apache-2.0" (at 278.13 95.25 0)
      (effects (font (size 1.27 1.27) (thickness 0.15)) (justify left bottom) hide)
    )
    (property "Author" "Antmicro" (at 278.13 97.79 0)
      (effects (font (size 1.27 1.27) (thickness 0.15)) (justify left bottom) hide)
    )
    (property "Tolerance" "1%" (at 278.13 80.01 0)
      (effects (font (size 1.27 1.27)) (justify left bottom) hide)
    )
    (property "Public" "False" (at 278.13 100.33 0)
      (effects (font (size 1.27 1.27)) (justify left bottom) hide)
    )
    (pin "1")
    (pin "2")
    (instances
      (project "ecp5-dc-scm"
        (path ""
          (reference "R113") (unit 1)
        )
      )
    )
  )

  (symbol (lib_id "antmicroResistors0402:R_10k_0402") (at 238.76 74.93 90) (mirror x) (unit 1)
    (in_bom yes) (on_board yes) (dnp no)
    (property "Reference" "R106" (at 236.22 76.2 90)
      (effects (font (size 1.524 1.524)) (justify left))
    )
    (property "Value" "R_10k_0402" (at 242.57 74.93 0)
      (effects (font (size 1.524 1.524)) hide)
    )
    (property "Footprint" "antmicro-footprints:R_0402_1005Metric" (at 233.68 80.01 0)
      (effects (font (size 1.524 1.524)) (justify left) hide)
    )
    (property "Datasheet" "https://www.bourns.com/docs/product-datasheets/cr.pdf" (at 238.76 74.93 0)
      (effects (font (size 1.27 1.27)) hide)
    )
    (property "Manufacturer" "Bourns" (at 228.6 80.01 0)
      (effects (font (size 1.524 1.524)) (justify left) hide)
    )
    (property "MPN" "CR0402-FX-1002GLF" (at 231.14 80.01 0)
      (effects (font (size 1.524 1.524)) (justify left) hide)
    )
    (property "Val" "10k" (at 236.22 78.74 90)
      (effects (font (size 1.27 1.27)) (justify left))
    )
    (property "License" "Apache-2.0" (at 264.16 95.25 0)
      (effects (font (size 1.27 1.27) (thickness 0.15)) (justify left bottom) hide)
    )
    (property "Author" "Antmicro" (at 266.7 95.25 0)
      (effects (font (size 1.27 1.27) (thickness 0.15)) (justify left bottom) hide)
    )
    (property "Tolerance" "1%" (at 248.92 95.25 0)
      (effects (font (size 1.27 1.27)) (justify left bottom) hide)
    )
    (property "Public" "False" (at 269.24 95.25 0)
      (effects (font (size 1.27 1.27)) (justify left bottom) hide)
    )
    (pin "1")
    (pin "2")
    (instances
      (project "ecp5-dc-scm"
        (path ""
          (reference "R106") (unit 1)
        )
      )
    )
  )

  (symbol (lib_id "antmicropower:GND") (at 254 92.71 0) (unit 1)
    (in_bom yes) (on_board yes) (dnp no)
    (property "Reference" "#PWR083" (at 254 99.06 0)
      (effects (font (size 1.27 1.27)) hide)
    )
    (property "Value" "GND" (at 254.127 97.1042 0)
      (effects (font (size 1.27 1.27)))
    )
    (property "Footprint" "" (at 254 92.71 0)
      (effects (font (size 1.27 1.27)) hide)
    )
    (property "Datasheet" "" (at 254 92.71 0)
      (effects (font (size 1.27 1.27)) hide)
    )
    (property "Author" "Antmicro" (at 262.89 100.33 0)
      (effects (font (size 1.27 1.27) (thickness 0.15)) (justify left bottom) hide)
    )
    (property "License" "Apache-2.0" (at 262.89 102.87 0)
      (effects (font (size 1.27 1.27) (thickness 0.15)) (justify left bottom) hide)
    )
    (pin "1")
    (instances
      (project "ecp5-dc-scm"
        (path ""
          (reference "#PWR083") (unit 1)
        )
      )
    )
  )

  (symbol (lib_id "antmicroTransistorsFETsMOSFETsSingle:2N7002_SOT-23-3") (at 246.38 49.53 0) (unit 1)
    (in_bom yes) (on_board yes) (dnp no) (fields_autoplaced)
    (property "Reference" "Q15" (at 257.175 45.72 0)
      (effects (font (size 1.524 1.524)) (justify left))
    )
    (property "Value" "2N7002" (at 257.175 48.26 0)
      (effects (font (size 1.524 1.524)) (justify left))
    )
    (property "Footprint" "antmicro-footprints:SOT-23-3" (at 251.46 44.45 0)
      (effects (font (size 1.524 1.524)) (justify left) hide)
    )
    (property "Datasheet" "https://www.onsemi.com/pub/Collateral/NDS7002A-D.PDF" (at 251.46 41.91 0)
      (effects (font (size 1.524 1.524)) (justify left) hide)
    )
    (property "MPN" "2N7002" (at 251.46 36.83 0)
      (effects (font (size 1.524 1.524)) (justify left) hide)
    )
    (property "Manufacturer" "ON Semiconductor" (at 251.46 21.59 0)
      (effects (font (size 1.524 1.524)) (justify left) hide)
    )
    (property "Author" "Antmicro" (at 269.24 69.85 0)
      (effects (font (size 1.27 1.27) (thickness 0.15)) (justify left bottom) hide)
    )
    (property "License" "Apache-2.0" (at 269.24 72.39 0)
      (effects (font (size 1.27 1.27) (thickness 0.15)) (justify left bottom) hide)
    )
    (pin "1")
    (pin "2")
    (pin "3")
    (instances
      (project "ecp5-dc-scm"
        (path ""
          (reference "Q15") (unit 1)
        )
      )
    )
  )

  (symbol (lib_id "antmicroResistors0402:R_1k_0402") (at 257.81 33.02 0) (unit 1)
    (in_bom yes) (on_board yes) (dnp no) (fields_autoplaced)
    (property "Reference" "R112" (at 260.35 36.83 0)
      (effects (font (size 1.524 1.524)))
    )
    (property "Value" "R_1k_0402" (at 257.81 36.83 0)
      (effects (font (size 1.524 1.524)) hide)
    )
    (property "Footprint" "antmicro-footprints:R_0402_1005Metric" (at 262.89 27.94 0)
      (effects (font (size 1.524 1.524)) (justify left) hide)
    )
    (property "Datasheet" "https://www.bourns.com/docs/product-datasheets/cr.pdf" (at 257.81 33.02 0)
      (effects (font (size 1.27 1.27)) hide)
    )
    (property "Manufacturer" "Bourns" (at 262.89 22.86 0)
      (effects (font (size 1.524 1.524)) (justify left) hide)
    )
    (property "MPN" "CR0402-FX-1001GLF" (at 262.89 25.4 0)
      (effects (font (size 1.524 1.524)) (justify left) hide)
    )
    (property "Val" "1k" (at 260.35 39.37 0)
      (effects (font (size 1.27 1.27)))
    )
    (property "License" "Apache-2.0" (at 278.13 58.42 0)
      (effects (font (size 1.27 1.27) (thickness 0.15)) (justify left bottom) hide)
    )
    (property "Author" "Antmicro" (at 278.13 60.96 0)
      (effects (font (size 1.27 1.27) (thickness 0.15)) (justify left bottom) hide)
    )
    (property "Tolerance" "1%" (at 278.13 43.18 0)
      (effects (font (size 1.27 1.27)) (justify left bottom) hide)
    )
    (property "Public" "False" (at 278.13 63.5 0)
      (effects (font (size 1.27 1.27)) (justify left bottom) hide)
    )
    (pin "1")
    (pin "2")
    (instances
      (project "ecp5-dc-scm"
        (path ""
          (reference "R112") (unit 1)
        )
      )
    )
  )

  (symbol (lib_id "antmicroResistors0402:R_10k_0402") (at 238.76 39.37 270) (unit 1)
    (in_bom yes) (on_board yes) (dnp no)
    (property "Reference" "R105" (at 239.395 35.56 90)
      (effects (font (size 1.524 1.524)) (justify left))
    )
    (property "Value" "R_10k_0402" (at 234.95 39.37 0)
      (effects (font (size 1.524 1.524)) hide)
    )
    (property "Footprint" "antmicro-footprints:R_0402_1005Metric" (at 243.84 44.45 0)
      (effects (font (size 1.524 1.524)) (justify left) hide)
    )
    (property "Datasheet" "https://www.bourns.com/docs/product-datasheets/cr.pdf" (at 238.76 39.37 0)
      (effects (font (size 1.27 1.27)) hide)
    )
    (property "Manufacturer" "Bourns" (at 248.92 44.45 0)
      (effects (font (size 1.524 1.524)) (justify left) hide)
    )
    (property "MPN" "CR0402-FX-1002GLF" (at 246.38 44.45 0)
      (effects (font (size 1.524 1.524)) (justify left) hide)
    )
    (property "Val" "10k" (at 240.03 42.545 90)
      (effects (font (size 1.27 1.27)) (justify left))
    )
    (property "License" "Apache-2.0" (at 213.36 59.69 0)
      (effects (font (size 1.27 1.27) (thickness 0.15)) (justify left bottom) hide)
    )
    (property "Author" "Antmicro" (at 210.82 59.69 0)
      (effects (font (size 1.27 1.27) (thickness 0.15)) (justify left bottom) hide)
    )
    (property "Tolerance" "1%" (at 228.6 59.69 0)
      (effects (font (size 1.27 1.27)) (justify left bottom) hide)
    )
    (property "Public" "False" (at 208.28 59.69 0)
      (effects (font (size 1.27 1.27)) (justify left bottom) hide)
    )
    (pin "1")
    (pin "2")
    (instances
      (project "ecp5-dc-scm"
        (path ""
          (reference "R105") (unit 1)
        )
      )
    )
  )

  (symbol (lib_id "antmicropower:GND") (at 254 55.88 0) (unit 1)
    (in_bom yes) (on_board yes) (dnp no)
    (property "Reference" "#PWR082" (at 254 62.23 0)
      (effects (font (size 1.27 1.27)) hide)
    )
    (property "Value" "GND" (at 254.127 60.2742 0)
      (effects (font (size 1.27 1.27)))
    )
    (property "Footprint" "" (at 254 55.88 0)
      (effects (font (size 1.27 1.27)) hide)
    )
    (property "Datasheet" "" (at 254 55.88 0)
      (effects (font (size 1.27 1.27)) hide)
    )
    (property "Author" "Antmicro" (at 262.89 63.5 0)
      (effects (font (size 1.27 1.27) (thickness 0.15)) (justify left bottom) hide)
    )
    (property "License" "Apache-2.0" (at 262.89 66.04 0)
      (effects (font (size 1.27 1.27) (thickness 0.15)) (justify left bottom) hide)
    )
    (pin "1")
    (instances
      (project "ecp5-dc-scm"
        (path ""
          (reference "#PWR082") (unit 1)
        )
      )
    )
  )

  (symbol (lib_id "antmicroTransistorsFETsMOSFETsSingle:2N7002_SOT-23-3") (at 246.38 238.76 0) (unit 1)
    (in_bom yes) (on_board yes) (dnp no) (fields_autoplaced)
    (property "Reference" "Q13" (at 257.175 234.95 0)
      (effects (font (size 1.524 1.524)) (justify left))
    )
    (property "Value" "2N7002" (at 257.175 237.49 0)
      (effects (font (size 1.524 1.524)) (justify left))
    )
    (property "Footprint" "antmicro-footprints:SOT-23-3" (at 251.46 233.68 0)
      (effects (font (size 1.524 1.524)) (justify left) hide)
    )
    (property "Datasheet" "https://www.onsemi.com/pub/Collateral/NDS7002A-D.PDF" (at 251.46 231.14 0)
      (effects (font (size 1.524 1.524)) (justify left) hide)
    )
    (property "MPN" "2N7002" (at 251.46 226.06 0)
      (effects (font (size 1.524 1.524)) (justify left) hide)
    )
    (property "Manufacturer" "ON Semiconductor" (at 251.46 210.82 0)
      (effects (font (size 1.524 1.524)) (justify left) hide)
    )
    (property "Author" "Antmicro" (at 269.24 259.08 0)
      (effects (font (size 1.27 1.27) (thickness 0.15)) (justify left bottom) hide)
    )
    (property "License" "Apache-2.0" (at 269.24 261.62 0)
      (effects (font (size 1.27 1.27) (thickness 0.15)) (justify left bottom) hide)
    )
    (pin "1")
    (pin "2")
    (pin "3")
    (instances
      (project "ecp5-dc-scm"
        (path ""
          (reference "Q13") (unit 1)
        )
      )
    )
  )

  (symbol (lib_id "antmicroResistors0402:R_1k_0402") (at 257.81 222.25 0) (unit 1)
    (in_bom yes) (on_board yes) (dnp no) (fields_autoplaced)
    (property "Reference" "R110" (at 260.35 226.06 0)
      (effects (font (size 1.524 1.524)))
    )
    (property "Value" "R_1k_0402" (at 257.81 226.06 0)
      (effects (font (size 1.524 1.524)) hide)
    )
    (property "Footprint" "antmicro-footprints:R_0402_1005Metric" (at 262.89 217.17 0)
      (effects (font (size 1.524 1.524)) (justify left) hide)
    )
    (property "Datasheet" "https://www.bourns.com/docs/product-datasheets/cr.pdf" (at 257.81 222.25 0)
      (effects (font (size 1.27 1.27)) hide)
    )
    (property "Manufacturer" "Bourns" (at 262.89 212.09 0)
      (effects (font (size 1.524 1.524)) (justify left) hide)
    )
    (property "MPN" "CR0402-FX-1001GLF" (at 262.89 214.63 0)
      (effects (font (size 1.524 1.524)) (justify left) hide)
    )
    (property "Val" "1k" (at 260.35 228.6 0)
      (effects (font (size 1.27 1.27)))
    )
    (property "License" "Apache-2.0" (at 278.13 247.65 0)
      (effects (font (size 1.27 1.27) (thickness 0.15)) (justify left bottom) hide)
    )
    (property "Author" "Antmicro" (at 278.13 250.19 0)
      (effects (font (size 1.27 1.27) (thickness 0.15)) (justify left bottom) hide)
    )
    (property "Tolerance" "1%" (at 278.13 232.41 0)
      (effects (font (size 1.27 1.27)) (justify left bottom) hide)
    )
    (property "Public" "False" (at 278.13 252.73 0)
      (effects (font (size 1.27 1.27)) (justify left bottom) hide)
    )
    (pin "1")
    (pin "2")
    (instances
      (project "ecp5-dc-scm"
        (path ""
          (reference "R110") (unit 1)
        )
      )
    )
  )

  (symbol (lib_id "antmicroResistors0402:R_10k_0402") (at 238.76 228.6 90) (mirror x) (unit 1)
    (in_bom yes) (on_board yes) (dnp no)
    (property "Reference" "R103" (at 236.22 229.87 90)
      (effects (font (size 1.524 1.524)) (justify left))
    )
    (property "Value" "R_10k_0402" (at 242.57 228.6 0)
      (effects (font (size 1.524 1.524)) hide)
    )
    (property "Footprint" "antmicro-footprints:R_0402_1005Metric" (at 233.68 233.68 0)
      (effects (font (size 1.524 1.524)) (justify left) hide)
    )
    (property "Datasheet" "https://www.bourns.com/docs/product-datasheets/cr.pdf" (at 238.76 228.6 0)
      (effects (font (size 1.27 1.27)) hide)
    )
    (property "Manufacturer" "Bourns" (at 228.6 233.68 0)
      (effects (font (size 1.524 1.524)) (justify left) hide)
    )
    (property "MPN" "CR0402-FX-1002GLF" (at 231.14 233.68 0)
      (effects (font (size 1.524 1.524)) (justify left) hide)
    )
    (property "Val" "10k" (at 236.22 232.41 90)
      (effects (font (size 1.27 1.27)) (justify left))
    )
    (property "License" "Apache-2.0" (at 264.16 248.92 0)
      (effects (font (size 1.27 1.27) (thickness 0.15)) (justify left bottom) hide)
    )
    (property "Author" "Antmicro" (at 266.7 248.92 0)
      (effects (font (size 1.27 1.27) (thickness 0.15)) (justify left bottom) hide)
    )
    (property "Tolerance" "1%" (at 248.92 248.92 0)
      (effects (font (size 1.27 1.27)) (justify left bottom) hide)
    )
    (property "Public" "False" (at 269.24 248.92 0)
      (effects (font (size 1.27 1.27)) (justify left bottom) hide)
    )
    (pin "1")
    (pin "2")
    (instances
      (project "ecp5-dc-scm"
        (path ""
          (reference "R103") (unit 1)
        )
      )
    )
  )

  (symbol (lib_id "antmicropower:GND") (at 254 245.11 0) (unit 1)
    (in_bom yes) (on_board yes) (dnp no)
    (property "Reference" "#PWR080" (at 254 251.46 0)
      (effects (font (size 1.27 1.27)) hide)
    )
    (property "Value" "GND" (at 254.127 249.5042 0)
      (effects (font (size 1.27 1.27)))
    )
    (property "Footprint" "" (at 254 245.11 0)
      (effects (font (size 1.27 1.27)) hide)
    )
    (property "Datasheet" "" (at 254 245.11 0)
      (effects (font (size 1.27 1.27)) hide)
    )
    (property "Author" "Antmicro" (at 262.89 252.73 0)
      (effects (font (size 1.27 1.27) (thickness 0.15)) (justify left bottom) hide)
    )
    (property "License" "Apache-2.0" (at 262.89 255.27 0)
      (effects (font (size 1.27 1.27) (thickness 0.15)) (justify left bottom) hide)
    )
    (pin "1")
    (instances
      (project "ecp5-dc-scm"
        (path ""
          (reference "#PWR080") (unit 1)
        )
      )
    )
  )

  (symbol (lib_id "antmicroResistors0402:R_10k_0402") (at 238.76 113.03 90) (mirror x) (unit 1)
    (in_bom yes) (on_board yes) (dnp no)
    (property "Reference" "R102" (at 236.22 114.3 90)
      (effects (font (size 1.524 1.524)) (justify left))
    )
    (property "Value" "R_10k_0402" (at 242.57 113.03 0)
      (effects (font (size 1.524 1.524)) hide)
    )
    (property "Footprint" "antmicro-footprints:R_0402_1005Metric" (at 233.68 118.11 0)
      (effects (font (size 1.524 1.524)) (justify left) hide)
    )
    (property "Datasheet" "https://www.bourns.com/docs/product-datasheets/cr.pdf" (at 238.76 113.03 0)
      (effects (font (size 1.27 1.27)) hide)
    )
    (property "Manufacturer" "Bourns" (at 228.6 118.11 0)
      (effects (font (size 1.524 1.524)) (justify left) hide)
    )
    (property "MPN" "CR0402-FX-1002GLF" (at 231.14 118.11 0)
      (effects (font (size 1.524 1.524)) (justify left) hide)
    )
    (property "Val" "10k" (at 236.22 116.84 90)
      (effects (font (size 1.27 1.27)) (justify left))
    )
    (property "License" "Apache-2.0" (at 264.16 133.35 0)
      (effects (font (size 1.27 1.27) (thickness 0.15)) (justify left bottom) hide)
    )
    (property "Author" "Antmicro" (at 266.7 133.35 0)
      (effects (font (size 1.27 1.27) (thickness 0.15)) (justify left bottom) hide)
    )
    (property "Tolerance" "1%" (at 248.92 133.35 0)
      (effects (font (size 1.27 1.27)) (justify left bottom) hide)
    )
    (property "Public" "False" (at 269.24 133.35 0)
      (effects (font (size 1.27 1.27)) (justify left bottom) hide)
    )
    (pin "1")
    (pin "2")
    (instances
      (project "ecp5-dc-scm"
        (path ""
          (reference "R102") (unit 1)
        )
      )
    )
  )

  (symbol (lib_id "antmicroResistors0402:R_1k_0402") (at 257.81 107.95 0) (unit 1)
    (in_bom yes) (on_board yes) (dnp no) (fields_autoplaced)
    (property "Reference" "R108" (at 260.35 111.76 0)
      (effects (font (size 1.524 1.524)))
    )
    (property "Value" "R_1k_0402" (at 257.81 111.76 0)
      (effects (font (size 1.524 1.524)) hide)
    )
    (property "Footprint" "antmicro-footprints:R_0402_1005Metric" (at 262.89 102.87 0)
      (effects (font (size 1.524 1.524)) (justify left) hide)
    )
    (property "Datasheet" "https://www.bourns.com/docs/product-datasheets/cr.pdf" (at 257.81 107.95 0)
      (effects (font (size 1.27 1.27)) hide)
    )
    (property "Manufacturer" "Bourns" (at 262.89 97.79 0)
      (effects (font (size 1.524 1.524)) (justify left) hide)
    )
    (property "MPN" "CR0402-FX-1001GLF" (at 262.89 100.33 0)
      (effects (font (size 1.524 1.524)) (justify left) hide)
    )
    (property "Val" "1k" (at 260.35 114.3 0)
      (effects (font (size 1.27 1.27)))
    )
    (property "License" "Apache-2.0" (at 278.13 133.35 0)
      (effects (font (size 1.27 1.27) (thickness 0.15)) (justify left bottom) hide)
    )
    (property "Author" "Antmicro" (at 278.13 135.89 0)
      (effects (font (size 1.27 1.27) (thickness 0.15)) (justify left bottom) hide)
    )
    (property "Tolerance" "1%" (at 278.13 118.11 0)
      (effects (font (size 1.27 1.27)) (justify left bottom) hide)
    )
    (property "Public" "False" (at 278.13 138.43 0)
      (effects (font (size 1.27 1.27)) (justify left bottom) hide)
    )
    (pin "1")
    (pin "2")
    (instances
      (project "ecp5-dc-scm"
        (path ""
          (reference "R108") (unit 1)
        )
      )
    )
  )

  (symbol (lib_id "antmicroTransistorsFETsMOSFETsSingle:2N7002_SOT-23-3") (at 246.38 124.46 0) (unit 1)
    (in_bom yes) (on_board yes) (dnp no) (fields_autoplaced)
    (property "Reference" "Q11" (at 257.81 120.65 0)
      (effects (font (size 1.524 1.524)) (justify left))
    )
    (property "Value" "2N7002" (at 257.81 123.19 0)
      (effects (font (size 1.524 1.524)) (justify left))
    )
    (property "Footprint" "antmicro-footprints:SOT-23-3" (at 251.46 119.38 0)
      (effects (font (size 1.524 1.524)) (justify left) hide)
    )
    (property "Datasheet" "https://www.onsemi.com/pub/Collateral/NDS7002A-D.PDF" (at 251.46 116.84 0)
      (effects (font (size 1.524 1.524)) (justify left) hide)
    )
    (property "MPN" "2N7002" (at 251.46 111.76 0)
      (effects (font (size 1.524 1.524)) (justify left) hide)
    )
    (property "Manufacturer" "ON Semiconductor" (at 251.46 96.52 0)
      (effects (font (size 1.524 1.524)) (justify left) hide)
    )
    (property "Author" "Antmicro" (at 269.24 144.78 0)
      (effects (font (size 1.27 1.27) (thickness 0.15)) (justify left bottom) hide)
    )
    (property "License" "Apache-2.0" (at 269.24 147.32 0)
      (effects (font (size 1.27 1.27) (thickness 0.15)) (justify left bottom) hide)
    )
    (pin "1")
    (pin "2")
    (pin "3")
    (instances
      (project "ecp5-dc-scm"
        (path ""
          (reference "Q11") (unit 1)
        )
      )
    )
  )

  (symbol (lib_id "antmicropower:GND") (at 254 130.81 0) (unit 1)
    (in_bom yes) (on_board yes) (dnp no)
    (property "Reference" "#PWR078" (at 254 137.16 0)
      (effects (font (size 1.27 1.27)) hide)
    )
    (property "Value" "GND" (at 254.127 135.2042 0)
      (effects (font (size 1.27 1.27)))
    )
    (property "Footprint" "" (at 254 130.81 0)
      (effects (font (size 1.27 1.27)) hide)
    )
    (property "Datasheet" "" (at 254 130.81 0)
      (effects (font (size 1.27 1.27)) hide)
    )
    (property "Author" "Antmicro" (at 262.89 138.43 0)
      (effects (font (size 1.27 1.27) (thickness 0.15)) (justify left bottom) hide)
    )
    (property "License" "Apache-2.0" (at 262.89 140.97 0)
      (effects (font (size 1.27 1.27) (thickness 0.15)) (justify left bottom) hide)
    )
    (pin "1")
    (instances
      (project "ecp5-dc-scm"
        (path ""
          (reference "#PWR078") (unit 1)
        )
      )
    )
  )

  (symbol (lib_id "antmicroResistors0402:R_1k_0402") (at 257.81 146.05 0) (unit 1)
    (in_bom yes) (on_board yes) (dnp no)
    (property "Reference" "R109" (at 260.35 143.51 0)
      (effects (font (size 1.524 1.524)))
    )
    (property "Value" "R_1k_0402" (at 257.81 149.86 0)
      (effects (font (size 1.524 1.524)) hide)
    )
    (property "Footprint" "antmicro-footprints:R_0402_1005Metric" (at 262.89 140.97 0)
      (effects (font (size 1.524 1.524)) (justify left) hide)
    )
    (property "Datasheet" "https://www.bourns.com/docs/product-datasheets/cr.pdf" (at 257.81 146.05 0)
      (effects (font (size 1.27 1.27)) hide)
    )
    (property "Manufacturer" "Bourns" (at 262.89 135.89 0)
      (effects (font (size 1.524 1.524)) (justify left) hide)
    )
    (property "MPN" "CR0402-FX-1001GLF" (at 262.89 138.43 0)
      (effects (font (size 1.524 1.524)) (justify left) hide)
    )
    (property "Val" "1k" (at 260.35 148.59 0)
      (effects (font (size 1.27 1.27)))
    )
    (property "License" "Apache-2.0" (at 278.13 171.45 0)
      (effects (font (size 1.27 1.27) (thickness 0.15)) (justify left bottom) hide)
    )
    (property "Author" "Antmicro" (at 278.13 173.99 0)
      (effects (font (size 1.27 1.27) (thickness 0.15)) (justify left bottom) hide)
    )
    (property "Tolerance" "1%" (at 278.13 156.21 0)
      (effects (font (size 1.27 1.27)) (justify left bottom) hide)
    )
    (property "Public" "False" (at 278.13 176.53 0)
      (effects (font (size 1.27 1.27)) (justify left bottom) hide)
    )
    (pin "1")
    (pin "2")
    (instances
      (project "ecp5-dc-scm"
        (path ""
          (reference "R109") (unit 1)
        )
      )
    )
  )

  (symbol (lib_id "antmicroTransistorsFETsMOSFETsSingle:2N7002_SOT-23-3") (at 246.38 162.56 0) (unit 1)
    (in_bom yes) (on_board yes) (dnp no) (fields_autoplaced)
    (property "Reference" "Q12" (at 257.175 158.75 0)
      (effects (font (size 1.524 1.524)) (justify left))
    )
    (property "Value" "2N7002" (at 257.175 161.29 0)
      (effects (font (size 1.524 1.524)) (justify left))
    )
    (property "Footprint" "antmicro-footprints:SOT-23-3" (at 251.46 157.48 0)
      (effects (font (size 1.524 1.524)) (justify left) hide)
    )
    (property "Datasheet" "https://www.onsemi.com/pub/Collateral/NDS7002A-D.PDF" (at 251.46 154.94 0)
      (effects (font (size 1.524 1.524)) (justify left) hide)
    )
    (property "MPN" "2N7002" (at 251.46 149.86 0)
      (effects (font (size 1.524 1.524)) (justify left) hide)
    )
    (property "Manufacturer" "ON Semiconductor" (at 251.46 134.62 0)
      (effects (font (size 1.524 1.524)) (justify left) hide)
    )
    (property "Author" "Antmicro" (at 269.24 182.88 0)
      (effects (font (size 1.27 1.27) (thickness 0.15)) (justify left bottom) hide)
    )
    (property "License" "Apache-2.0" (at 269.24 185.42 0)
      (effects (font (size 1.27 1.27) (thickness 0.15)) (justify left bottom) hide)
    )
    (pin "1")
    (pin "2")
    (pin "3")
    (instances
      (project "ecp5-dc-scm"
        (path ""
          (reference "Q12") (unit 1)
        )
      )
    )
  )

  (symbol (lib_id "antmicropower:GND") (at 254 168.91 0) (unit 1)
    (in_bom yes) (on_board yes) (dnp no)
    (property "Reference" "#PWR079" (at 254 175.26 0)
      (effects (font (size 1.27 1.27)) hide)
    )
    (property "Value" "GND" (at 254.127 173.3042 0)
      (effects (font (size 1.27 1.27)))
    )
    (property "Footprint" "" (at 254 168.91 0)
      (effects (font (size 1.27 1.27)) hide)
    )
    (property "Datasheet" "" (at 254 168.91 0)
      (effects (font (size 1.27 1.27)) hide)
    )
    (property "Author" "Antmicro" (at 262.89 176.53 0)
      (effects (font (size 1.27 1.27) (thickness 0.15)) (justify left bottom) hide)
    )
    (property "License" "Apache-2.0" (at 262.89 179.07 0)
      (effects (font (size 1.27 1.27) (thickness 0.15)) (justify left bottom) hide)
    )
    (pin "1")
    (instances
      (project "ecp5-dc-scm"
        (path ""
          (reference "#PWR079") (unit 1)
        )
      )
    )
  )

  (symbol (lib_id "antmicroResistors0402:R_470k_0402") (at 187.96 135.89 270) (unit 1)
    (in_bom yes) (on_board yes) (dnp no) (fields_autoplaced)
    (property "Reference" "R99" (at 185.42 137.16 90)
      (effects (font (size 1.524 1.524)) (justify right))
    )
    (property "Value" "R_470k_0402" (at 184.15 135.89 0)
      (effects (font (size 1.524 1.524)) hide)
    )
    (property "Footprint" "antmicro-footprints:R_0402_1005Metric" (at 193.04 140.97 0)
      (effects (font (size 1.524 1.524)) (justify left) hide)
    )
    (property "Datasheet" "https://www.bourns.com/docs/product-datasheets/cr.pdf" (at 187.96 135.89 0)
      (effects (font (size 1.27 1.27)) hide)
    )
    (property "Manufacturer" "Bourns" (at 198.12 140.97 0)
      (effects (font (size 1.524 1.524)) (justify left) hide)
    )
    (property "MPN" "CR0402-FX-4703GLF" (at 195.58 140.97 0)
      (effects (font (size 1.524 1.524)) (justify left) hide)
    )
    (property "Val" "470k" (at 185.42 139.7 90)
      (effects (font (size 1.27 1.27)) (justify right))
    )
    (property "License" "Apache-2.0" (at 162.56 156.21 0)
      (effects (font (size 1.27 1.27) (thickness 0.15)) (justify left bottom) hide)
    )
    (property "Author" "Antmicro" (at 160.02 156.21 0)
      (effects (font (size 1.27 1.27) (thickness 0.15)) (justify left bottom) hide)
    )
    (property "Tolerance" "1%" (at 177.8 156.21 0)
      (effects (font (size 1.27 1.27)) (justify left bottom) hide)
    )
    (property "Public" "False" (at 157.48 156.21 0)
      (effects (font (size 1.27 1.27)) (justify left bottom) hide)
    )
    (pin "1")
    (pin "2")
    (instances
      (project "ecp5-dc-scm"
        (path ""
          (reference "R99") (unit 1)
        )
      )
    )
  )

  (symbol (lib_id "antmicroResistors0402:R_10k_0402") (at 187.96 144.78 270) (unit 1)
    (in_bom yes) (on_board yes) (dnp no) (fields_autoplaced)
    (property "Reference" "R100" (at 190.5 146.05 90)
      (effects (font (size 1.524 1.524)) (justify left))
    )
    (property "Value" "R_10k_0402" (at 184.15 144.78 0)
      (effects (font (size 1.524 1.524)) hide)
    )
    (property "Footprint" "antmicro-footprints:R_0402_1005Metric" (at 193.04 149.86 0)
      (effects (font (size 1.524 1.524)) (justify left) hide)
    )
    (property "Datasheet" "https://www.bourns.com/docs/product-datasheets/cr.pdf" (at 187.96 144.78 0)
      (effects (font (size 1.27 1.27)) hide)
    )
    (property "Manufacturer" "Bourns" (at 198.12 149.86 0)
      (effects (font (size 1.524 1.524)) (justify left) hide)
    )
    (property "MPN" "CR0402-FX-1002GLF" (at 195.58 149.86 0)
      (effects (font (size 1.524 1.524)) (justify left) hide)
    )
    (property "Val" "10k" (at 190.5 148.59 90)
      (effects (font (size 1.27 1.27)) (justify left))
    )
    (property "License" "Apache-2.0" (at 162.56 165.1 0)
      (effects (font (size 1.27 1.27) (thickness 0.15)) (justify left bottom) hide)
    )
    (property "Author" "Antmicro" (at 160.02 165.1 0)
      (effects (font (size 1.27 1.27) (thickness 0.15)) (justify left bottom) hide)
    )
    (property "Tolerance" "1%" (at 177.8 165.1 0)
      (effects (font (size 1.27 1.27)) (justify left bottom) hide)
    )
    (property "Public" "False" (at 157.48 165.1 0)
      (effects (font (size 1.27 1.27)) (justify left bottom) hide)
    )
    (pin "1")
    (pin "2")
    (instances
      (project "ecp5-dc-scm"
        (path ""
          (reference "R100") (unit 1)
        )
      )
    )
  )

  (symbol (lib_id "antmicroFixedInductors:L_470n_6.7A_Vishay-IHLP-1212AE-11") (at 356.87 36.83 0) (unit 1)
    (in_bom yes) (on_board yes) (dnp no) (fields_autoplaced)
    (property "Reference" "L7" (at 359.41 31.75 0)
      (effects (font (size 1.524 1.524)))
    )
    (property "Value" "IHLP1212AEERR47M11" (at 359.41 33.655 0)
      (effects (font (size 1.524 1.524)) hide)
    )
    (property "Footprint" "antmicro-footprints:L_Vishay-IHLP-1212AE" (at 356.87 36.83 0)
      (effects (font (size 1.524 1.524)) hide)
    )
    (property "Datasheet" "https://www.vishay.com/docs/34300/ihlp-1212ae-11.pdf" (at 356.87 36.83 0)
      (effects (font (size 1.524 1.524)) hide)
    )
    (property "Manufacturer" "Vishay" (at 356.87 36.83 0)
      (effects (font (size 1.27 1.27)) hide)
    )
    (property "MPN" "IHLP1212AEERR47M11" (at 356.87 36.83 0)
      (effects (font (size 1.27 1.27)) hide)
    )
    (property "Val" "470n/6.7A" (at 359.41 34.29 0)
      (effects (font (size 1.27 1.27) (thickness 0.15)))
    )
    (property "ISat" "6.7 A" (at 370.84 53.34 0)
      (effects (font (size 1.27 1.27)) (justify left) hide)
    )
    (property "IMax" "6.7 A" (at 370.84 57.15 0)
      (effects (font (size 1.27 1.27) (thickness 0.15)) (justify left bottom) hide)
    )
    (property "Size" "3.0x3.0" (at 370.84 59.69 0)
      (effects (font (size 1.27 1.27) (thickness 0.15)) (justify left bottom) hide)
    )
    (property "Author" "Antmicro" (at 370.84 62.23 0)
      (effects (font (size 1.27 1.27) (thickness 0.15)) (justify left bottom) hide)
    )
    (property "License" "Apache-2.0" (at 370.84 64.77 0)
      (effects (font (size 1.27 1.27) (thickness 0.15)) (justify left bottom) hide)
    )
    (property "Public" "False" (at 370.84 67.31 0)
      (effects (font (size 1.27 1.27)) (justify left bottom) hide)
    )
    (pin "1")
    (pin "2")
    (instances
      (project "ecp5-dc-scm"
        (path ""
          (reference "L7") (unit 1)
        )
      )
    )
  )

  (symbol (lib_id "antmicroResistors0402:R_66k5_0402") (at 372.11 231.14 90) (unit 1)
    (in_bom yes) (on_board yes) (dnp no) (fields_autoplaced)
    (property "Reference" "R120" (at 374.65 227.33 90)
      (effects (font (size 1.524 1.524)) (justify right))
    )
    (property "Value" "R_66k5_0402" (at 375.92 231.14 0)
      (effects (font (size 1.524 1.524)) hide)
    )
    (property "Footprint" "antmicro-footprints:R_0402_1005Metric" (at 367.03 226.06 0)
      (effects (font (size 1.524 1.524)) (justify left) hide)
    )
    (property "Datasheet" "https://www.bourns.com/docs/product-datasheets/cr.pdf" (at 372.11 231.14 0)
      (effects (font (size 1.27 1.27)) hide)
    )
    (property "Manufacturer" "Bourns" (at 361.95 226.06 0)
      (effects (font (size 1.524 1.524)) (justify left) hide)
    )
    (property "MPN" "CR0402-FX-6652GLF" (at 364.49 226.06 0)
      (effects (font (size 1.524 1.524)) (justify left) hide)
    )
    (property "Val" "66k5" (at 374.65 229.87 90)
      (effects (font (size 1.27 1.27)) (justify right))
    )
    (property "License" "Apache-2.0" (at 397.51 210.82 0)
      (effects (font (size 1.27 1.27) (thickness 0.15)) (justify left bottom) hide)
    )
    (property "Author" "Antmicro" (at 400.05 210.82 0)
      (effects (font (size 1.27 1.27) (thickness 0.15)) (justify left bottom) hide)
    )
    (property "Tolerance" "1%" (at 382.27 210.82 0)
      (effects (font (size 1.27 1.27)) (justify left bottom) hide)
    )
    (property "Public" "False" (at 402.59 210.82 0)
      (effects (font (size 1.27 1.27)) (justify left bottom) hide)
    )
    (pin "1")
    (pin "2")
    (instances
      (project "ecp5-dc-scm"
        (path ""
          (reference "R120") (unit 1)
        )
      )
    )
  )

  (symbol (lib_id "antmicroCapacitors0603:C_10u_25V_0603") (at 78.74 66.04 90) (unit 1)
    (in_bom yes) (on_board yes) (dnp no)
    (property "Reference" "C101" (at 76.2 66.04 0)
      (effects (font (size 1.524 1.524)) (justify left))
    )
    (property "Value" "C_10u_25V_0603" (at 82.55 66.04 0)
      (effects (font (size 1.524 1.524)) hide)
    )
    (property "Footprint" "antmicro-footprints:C_0603_1608Metric" (at 73.66 60.96 0)
      (effects (font (size 1.524 1.524)) (justify left) hide)
    )
    (property "Datasheet" "https://product.tdk.com/en/search/capacitor/ceramic/mlcc/info?part_no=C1608X5R1E106M080AC" (at 78.74 66.04 0)
      (effects (font (size 1.27 1.27)) hide)
    )
    (property "Manufacturer" "TDK" (at 68.58 60.96 0)
      (effects (font (size 1.524 1.524)) (justify left) hide)
    )
    (property "MPN" "C1608X5R1E106M080AC" (at 71.12 60.96 0)
      (effects (font (size 1.524 1.524)) (justify left) hide)
    )
    (property "Val" "10u" (at 81.28 66.04 0)
      (effects (font (size 1.27 1.27)) (justify left))
    )
    (property "License" "Apache-2.0" (at 101.6 45.72 0)
      (effects (font (size 1.27 1.27) (thickness 0.15)) (justify left bottom) hide)
    )
    (property "Author" "Antmicro" (at 104.14 45.72 0)
      (effects (font (size 1.27 1.27) (thickness 0.15)) (justify left bottom) hide)
    )
    (property "Voltage" "25V" (at 106.68 45.72 0)
      (effects (font (size 1.27 1.27)) (justify left bottom) hide)
    )
    (property "Dielectric" "" (at 109.22 45.72 0)
      (effects (font (size 1.27 1.27)) (justify left bottom) hide)
    )
    (property "Public" "False" (at 111.76 45.72 0)
      (effects (font (size 1.27 1.27)) (justify left bottom) hide)
    )
    (pin "1")
    (pin "2")
    (instances
      (project "ecp5-dc-scm"
        (path ""
          (reference "C101") (unit 1)
        )
      )
    )
  )

  (symbol (lib_id "antmicroCapacitors0402:C_10u_0402") (at 48.26 237.49 90) (unit 1)
    (in_bom yes) (on_board yes) (dnp no) (fields_autoplaced)
    (property "Reference" "C262" (at 45.085 233.6736 90)
      (effects (font (size 1.524 1.524)) (justify left))
    )
    (property "Value" "C_10u_0402" (at 52.07 237.49 0)
      (effects (font (size 1.524 1.524)) hide)
    )
    (property "Footprint" "antmicro-footprints:C_0402_1005Metric" (at 43.18 232.41 0)
      (effects (font (size 1.524 1.524)) (justify left) hide)
    )
    (property "Datasheet" "https://www.yageo.com/en/Chart/Download/pdf/CC0402MRX5R5BB106" (at 48.26 237.49 0)
      (effects (font (size 1.27 1.27)) hide)
    )
    (property "Manufacturer" "YAGEO" (at 38.1 232.41 0)
      (effects (font (size 1.524 1.524)) (justify left) hide)
    )
    (property "MPN" "CC0402MRX5R5BB106" (at 40.64 232.41 0)
      (effects (font (size 1.524 1.524)) (justify left) hide)
    )
    (property "Val" "10u" (at 45.085 236.2136 90)
      (effects (font (size 1.27 1.27)) (justify left))
    )
    (property "License" "Apache-2.0" (at 71.12 217.17 0)
      (effects (font (size 1.27 1.27) (thickness 0.15)) (justify left bottom) hide)
    )
    (property "Author" "Antmicro" (at 73.66 217.17 0)
      (effects (font (size 1.27 1.27) (thickness 0.15)) (justify left bottom) hide)
    )
    (property "Voltage" "" (at 76.2 217.17 0)
      (effects (font (size 1.27 1.27)) (justify left bottom) hide)
    )
    (property "Dielectric" "" (at 78.74 217.17 0)
      (effects (font (size 1.27 1.27)) (justify left bottom) hide)
    )
    (property "Public" "False" (at 81.28 217.17 0)
      (effects (font (size 1.27 1.27)) (justify left bottom) hide)
    )
    (pin "1")
    (pin "2")
    (instances
      (project "ecp5-dc-scm"
        (path ""
          (reference "C262") (unit 1)
        )
      )
    )
  )

  (symbol (lib_id "antmicroResistors0402:R_100k_0402") (at 48.26 212.09 270) (unit 1)
    (in_bom yes) (on_board yes) (dnp no) (fields_autoplaced)
    (property "Reference" "R8" (at 50.165 213.36 90)
      (effects (font (size 1.524 1.524)) (justify left))
    )
    (property "Value" "R_100k_0402" (at 44.45 212.09 0)
      (effects (font (size 1.524 1.524)) hide)
    )
    (property "Footprint" "antmicro-footprints:R_0402_1005Metric" (at 53.34 217.17 0)
      (effects (font (size 1.524 1.524)) (justify left) hide)
    )
    (property "Datasheet" "https://www.bourns.com/docs/product-datasheets/cr.pdf" (at 48.26 212.09 0)
      (effects (font (size 1.27 1.27)) hide)
    )
    (property "Manufacturer" "Bourns" (at 58.42 217.17 0)
      (effects (font (size 1.524 1.524)) (justify left) hide)
    )
    (property "MPN" "CR0402-FX-1003GLF" (at 55.88 217.17 0)
      (effects (font (size 1.524 1.524)) (justify left) hide)
    )
    (property "Val" "100k" (at 50.165 215.9 90)
      (effects (font (size 1.27 1.27)) (justify left))
    )
    (property "License" "Apache-2.0" (at 22.86 232.41 0)
      (effects (font (size 1.27 1.27) (thickness 0.15)) (justify left bottom) hide)
    )
    (property "Author" "Antmicro" (at 20.32 232.41 0)
      (effects (font (size 1.27 1.27) (thickness 0.15)) (justify left bottom) hide)
    )
    (property "Tolerance" "1%" (at 38.1 232.41 0)
      (effects (font (size 1.27 1.27)) (justify left bottom) hide)
    )
    (property "Public" "False" (at 17.78 232.41 0)
      (effects (font (size 1.27 1.27)) (justify left bottom) hide)
    )
    (pin "1")
    (pin "2")
    (instances
      (project "ecp5-dc-scm"
        (path ""
          (reference "R8") (unit 1)
        )
      )
    )
  )

  (symbol (lib_id "antmicroCapacitors0603:C_10u_25V_0603") (at 87.63 66.04 90) (unit 1)
    (in_bom yes) (on_board yes) (dnp no)
    (property "Reference" "C260" (at 85.09 66.04 0)
      (effects (font (size 1.524 1.524)) (justify left))
    )
    (property "Value" "C_10u_25V_0603" (at 91.44 66.04 0)
      (effects (font (size 1.524 1.524)) hide)
    )
    (property "Footprint" "antmicro-footprints:C_0603_1608Metric" (at 82.55 60.96 0)
      (effects (font (size 1.524 1.524)) (justify left) hide)
    )
    (property "Datasheet" "https://product.tdk.com/en/search/capacitor/ceramic/mlcc/info?part_no=C1608X5R1E106M080AC" (at 87.63 66.04 0)
      (effects (font (size 1.27 1.27)) hide)
    )
    (property "Manufacturer" "TDK" (at 77.47 60.96 0)
      (effects (font (size 1.524 1.524)) (justify left) hide)
    )
    (property "MPN" "C1608X5R1E106M080AC" (at 80.01 60.96 0)
      (effects (font (size 1.524 1.524)) (justify left) hide)
    )
    (property "Val" "10u" (at 90.17 66.04 0)
      (effects (font (size 1.27 1.27)) (justify left))
    )
    (property "License" "Apache-2.0" (at 110.49 45.72 0)
      (effects (font (size 1.27 1.27) (thickness 0.15)) (justify left bottom) hide)
    )
    (property "Author" "Antmicro" (at 113.03 45.72 0)
      (effects (font (size 1.27 1.27) (thickness 0.15)) (justify left bottom) hide)
    )
    (property "Voltage" "25V" (at 115.57 45.72 0)
      (effects (font (size 1.27 1.27)) (justify left bottom) hide)
    )
    (property "Dielectric" "" (at 118.11 45.72 0)
      (effects (font (size 1.27 1.27)) (justify left bottom) hide)
    )
    (property "Public" "False" (at 120.65 45.72 0)
      (effects (font (size 1.27 1.27)) (justify left bottom) hide)
    )
    (pin "1")
    (pin "2")
    (instances
      (project "ecp5-dc-scm"
        (path ""
          (reference "C260") (unit 1)
        )
      )
    )
  )

  (symbol (lib_id "antmicroCapacitors0603:C_10u_25V_0603") (at 96.52 66.04 90) (unit 1)
    (in_bom yes) (on_board yes) (dnp no)
    (property "Reference" "C261" (at 93.98 66.04 0)
      (effects (font (size 1.524 1.524)) (justify left))
    )
    (property "Value" "C_10u_25V_0603" (at 100.33 66.04 0)
      (effects (font (size 1.524 1.524)) hide)
    )
    (property "Footprint" "antmicro-footprints:C_0603_1608Metric" (at 91.44 60.96 0)
      (effects (font (size 1.524 1.524)) (justify left) hide)
    )
    (property "Datasheet" "https://product.tdk.com/en/search/capacitor/ceramic/mlcc/info?part_no=C1608X5R1E106M080AC" (at 96.52 66.04 0)
      (effects (font (size 1.27 1.27)) hide)
    )
    (property "Manufacturer" "TDK" (at 86.36 60.96 0)
      (effects (font (size 1.524 1.524)) (justify left) hide)
    )
    (property "MPN" "C1608X5R1E106M080AC" (at 88.9 60.96 0)
      (effects (font (size 1.524 1.524)) (justify left) hide)
    )
    (property "Val" "10u" (at 99.06 66.04 0)
      (effects (font (size 1.27 1.27)) (justify left))
    )
    (property "License" "Apache-2.0" (at 119.38 45.72 0)
      (effects (font (size 1.27 1.27) (thickness 0.15)) (justify left bottom) hide)
    )
    (property "Author" "Antmicro" (at 121.92 45.72 0)
      (effects (font (size 1.27 1.27) (thickness 0.15)) (justify left bottom) hide)
    )
    (property "Voltage" "25V" (at 124.46 45.72 0)
      (effects (font (size 1.27 1.27)) (justify left bottom) hide)
    )
    (property "Dielectric" "" (at 127 45.72 0)
      (effects (font (size 1.27 1.27)) (justify left bottom) hide)
    )
    (property "Public" "False" (at 129.54 45.72 0)
      (effects (font (size 1.27 1.27)) (justify left bottom) hide)
    )
    (pin "1")
    (pin "2")
    (instances
      (project "ecp5-dc-scm"
        (path ""
          (reference "C261") (unit 1)
        )
      )
    )
  )

  (symbol (lib_id "antmicroResistors0402:R_100k_0402") (at 87.63 213.36 270) (unit 1)
    (in_bom yes) (on_board yes) (dnp no)
    (property "Reference" "R85" (at 96.52 207.01 90)
      (effects (font (size 1.524 1.524)) (justify left))
    )
    (property "Value" "R_100k_0402" (at 83.82 213.36 0)
      (effects (font (size 1.524 1.524)) hide)
    )
    (property "Footprint" "antmicro-footprints:R_0402_1005Metric" (at 92.71 218.44 0)
      (effects (font (size 1.524 1.524)) (justify left) hide)
    )
    (property "Datasheet" "https://www.bourns.com/docs/product-datasheets/cr.pdf" (at 87.63 213.36 0)
      (effects (font (size 1.27 1.27)) hide)
    )
    (property "Manufacturer" "Bourns" (at 97.79 218.44 0)
      (effects (font (size 1.524 1.524)) (justify left) hide)
    )
    (property "MPN" "CR0402-FX-1003GLF" (at 95.25 218.44 0)
      (effects (font (size 1.524 1.524)) (justify left) hide)
    )
    (property "Val" "100k" (at 101.6 207.01 90)
      (effects (font (size 1.27 1.27)) (justify left))
    )
    (property "License" "Apache-2.0" (at 62.23 233.68 0)
      (effects (font (size 1.27 1.27) (thickness 0.15)) (justify left bottom) hide)
    )
    (property "Author" "Antmicro" (at 59.69 233.68 0)
      (effects (font (size 1.27 1.27) (thickness 0.15)) (justify left bottom) hide)
    )
    (property "Tolerance" "1%" (at 77.47 233.68 0)
      (effects (font (size 1.27 1.27)) (justify left bottom) hide)
    )
    (property "Public" "False" (at 57.15 233.68 0)
      (effects (font (size 1.27 1.27)) (justify left bottom) hide)
    )
    (pin "1")
    (pin "2")
    (instances
      (project "ecp5-dc-scm"
        (path ""
          (reference "R85") (unit 1)
        )
      )
    )
  )

  (symbol (lib_id "antmicroResistors0402:R_100k_0402") (at 90.17 213.36 270) (unit 1)
    (in_bom yes) (on_board yes) (dnp no)
    (property "Reference" "R86" (at 96.52 208.915 90)
      (effects (font (size 1.524 1.524)) (justify left))
    )
    (property "Value" "R_100k_0402" (at 86.36 213.36 0)
      (effects (font (size 1.524 1.524)) hide)
    )
    (property "Footprint" "antmicro-footprints:R_0402_1005Metric" (at 95.25 218.44 0)
      (effects (font (size 1.524 1.524)) (justify left) hide)
    )
    (property "Datasheet" "https://www.bourns.com/docs/product-datasheets/cr.pdf" (at 90.17 213.36 0)
      (effects (font (size 1.27 1.27)) hide)
    )
    (property "Manufacturer" "Bourns" (at 100.33 218.44 0)
      (effects (font (size 1.524 1.524)) (justify left) hide)
    )
    (property "MPN" "CR0402-FX-1003GLF" (at 97.79 218.44 0)
      (effects (font (size 1.524 1.524)) (justify left) hide)
    )
    (property "Val" "100k" (at 101.6 208.915 90)
      (effects (font (size 1.27 1.27)) (justify left))
    )
    (property "License" "Apache-2.0" (at 64.77 233.68 0)
      (effects (font (size 1.27 1.27) (thickness 0.15)) (justify left bottom) hide)
    )
    (property "Author" "Antmicro" (at 62.23 233.68 0)
      (effects (font (size 1.27 1.27) (thickness 0.15)) (justify left bottom) hide)
    )
    (property "Tolerance" "1%" (at 80.01 233.68 0)
      (effects (font (size 1.27 1.27)) (justify left bottom) hide)
    )
    (property "Public" "False" (at 59.69 233.68 0)
      (effects (font (size 1.27 1.27)) (justify left bottom) hide)
    )
    (pin "1")
    (pin "2")
    (instances
      (project "ecp5-dc-scm"
        (path ""
          (reference "R86") (unit 1)
        )
      )
    )
  )

  (symbol (lib_id "antmicroResistors0402:R_100k_0402") (at 92.71 213.36 270) (unit 1)
    (in_bom yes) (on_board yes) (dnp no)
    (property "Reference" "R87" (at 96.52 210.82 90)
      (effects (font (size 1.524 1.524)) (justify left))
    )
    (property "Value" "R_100k_0402" (at 88.9 213.36 0)
      (effects (font (size 1.524 1.524)) hide)
    )
    (property "Footprint" "antmicro-footprints:R_0402_1005Metric" (at 97.79 218.44 0)
      (effects (font (size 1.524 1.524)) (justify left) hide)
    )
    (property "Datasheet" "https://www.bourns.com/docs/product-datasheets/cr.pdf" (at 92.71 213.36 0)
      (effects (font (size 1.27 1.27)) hide)
    )
    (property "Manufacturer" "Bourns" (at 102.87 218.44 0)
      (effects (font (size 1.524 1.524)) (justify left) hide)
    )
    (property "MPN" "CR0402-FX-1003GLF" (at 100.33 218.44 0)
      (effects (font (size 1.524 1.524)) (justify left) hide)
    )
    (property "Val" "100k" (at 101.6 210.82 90)
      (effects (font (size 1.27 1.27)) (justify left))
    )
    (property "License" "Apache-2.0" (at 67.31 233.68 0)
      (effects (font (size 1.27 1.27) (thickness 0.15)) (justify left bottom) hide)
    )
    (property "Author" "Antmicro" (at 64.77 233.68 0)
      (effects (font (size 1.27 1.27) (thickness 0.15)) (justify left bottom) hide)
    )
    (property "Tolerance" "1%" (at 82.55 233.68 0)
      (effects (font (size 1.27 1.27)) (justify left bottom) hide)
    )
    (property "Public" "False" (at 62.23 233.68 0)
      (effects (font (size 1.27 1.27)) (justify left bottom) hide)
    )
    (pin "1")
    (pin "2")
    (instances
      (project "ecp5-dc-scm"
        (path ""
          (reference "R87") (unit 1)
        )
      )
    )
  )

  (symbol (lib_id "antmicropower:GND") (at 87.63 72.39 0) (unit 1)
    (in_bom yes) (on_board yes) (dnp no)
    (property "Reference" "#PWR0154" (at 87.63 78.74 0)
      (effects (font (size 1.27 1.27)) hide)
    )
    (property "Value" "GND" (at 87.757 76.7842 0)
      (effects (font (size 1.27 1.27)))
    )
    (property "Footprint" "" (at 87.63 72.39 0)
      (effects (font (size 1.27 1.27)) hide)
    )
    (property "Datasheet" "" (at 87.63 72.39 0)
      (effects (font (size 1.27 1.27)) hide)
    )
    (property "Author" "Antmicro" (at 96.52 80.01 0)
      (effects (font (size 1.27 1.27) (thickness 0.15)) (justify left bottom) hide)
    )
    (property "License" "Apache-2.0" (at 96.52 82.55 0)
      (effects (font (size 1.27 1.27) (thickness 0.15)) (justify left bottom) hide)
    )
    (pin "1")
    (instances
      (project "ecp5-dc-scm"
        (path ""
          (reference "#PWR0154") (unit 1)
        )
      )
    )
  )

  (symbol (lib_id "antmicropower:GND") (at 96.52 72.39 0) (unit 1)
    (in_bom yes) (on_board yes) (dnp no)
    (property "Reference" "#PWR0155" (at 96.52 78.74 0)
      (effects (font (size 1.27 1.27)) hide)
    )
    (property "Value" "GND" (at 96.647 76.7842 0)
      (effects (font (size 1.27 1.27)))
    )
    (property "Footprint" "" (at 96.52 72.39 0)
      (effects (font (size 1.27 1.27)) hide)
    )
    (property "Datasheet" "" (at 96.52 72.39 0)
      (effects (font (size 1.27 1.27)) hide)
    )
    (property "Author" "Antmicro" (at 105.41 80.01 0)
      (effects (font (size 1.27 1.27) (thickness 0.15)) (justify left bottom) hide)
    )
    (property "License" "Apache-2.0" (at 105.41 82.55 0)
      (effects (font (size 1.27 1.27) (thickness 0.15)) (justify left bottom) hide)
    )
    (pin "1")
    (instances
      (project "ecp5-dc-scm"
        (path ""
          (reference "#PWR0155") (unit 1)
        )
      )
    )
  )

  (symbol (lib_id "antmicropower:GND") (at 48.26 238.76 0) (unit 1)
    (in_bom yes) (on_board yes) (dnp no)
    (property "Reference" "#PWR029" (at 48.26 245.11 0)
      (effects (font (size 1.27 1.27)) hide)
    )
    (property "Value" "GND" (at 50.165 243.205 0)
      (effects (font (size 1.27 1.27)) (justify right))
    )
    (property "Footprint" "" (at 48.26 238.76 0)
      (effects (font (size 1.27 1.27)) hide)
    )
    (property "Datasheet" "" (at 48.26 238.76 0)
      (effects (font (size 1.27 1.27)) hide)
    )
    (property "Author" "Antmicro" (at 57.15 246.38 0)
      (effects (font (size 1.27 1.27) (thickness 0.15)) (justify left bottom) hide)
    )
    (property "License" "Apache-2.0" (at 57.15 248.92 0)
      (effects (font (size 1.27 1.27) (thickness 0.15)) (justify left bottom) hide)
    )
    (pin "1")
    (instances
      (project "ecp5-dc-scm"
        (path ""
          (reference "#PWR029") (unit 1)
        )
      )
    )
  )

  (symbol (lib_id "antmicropower:GND") (at 78.74 72.39 0) (unit 1)
    (in_bom yes) (on_board yes) (dnp no)
    (property "Reference" "#PWR063" (at 78.74 78.74 0)
      (effects (font (size 1.27 1.27)) hide)
    )
    (property "Value" "GND" (at 78.867 76.7842 0)
      (effects (font (size 1.27 1.27)))
    )
    (property "Footprint" "" (at 78.74 72.39 0)
      (effects (font (size 1.27 1.27)) hide)
    )
    (property "Datasheet" "" (at 78.74 72.39 0)
      (effects (font (size 1.27 1.27)) hide)
    )
    (property "Author" "Antmicro" (at 87.63 80.01 0)
      (effects (font (size 1.27 1.27) (thickness 0.15)) (justify left bottom) hide)
    )
    (property "License" "Apache-2.0" (at 87.63 82.55 0)
      (effects (font (size 1.27 1.27) (thickness 0.15)) (justify left bottom) hide)
    )
    (pin "1")
    (instances
      (project "ecp5-dc-scm"
        (path ""
          (reference "#PWR063") (unit 1)
        )
      )
    )
  )

  (symbol (lib_id "antmicroResistors0402:R_243k_0402") (at 109.22 68.58 90) (unit 1)
    (in_bom yes) (on_board yes) (dnp no)
    (property "Reference" "R91" (at 105.41 64.77 90)
      (effects (font (size 1.524 1.524)))
    )
    (property "Value" "R_243k_0402" (at 113.03 68.58 0)
      (effects (font (size 1.524 1.524)) hide)
    )
    (property "Footprint" "antmicro-footprints:R_0402_1005Metric" (at 104.14 63.5 0)
      (effects (font (size 1.524 1.524)) (justify left) hide)
    )
    (property "Datasheet" "https://www.bourns.com/docs/product-datasheets/cr.pdf" (at 109.22 68.58 0)
      (effects (font (size 1.27 1.27)) hide)
    )
    (property "Manufacturer" "Bourns" (at 99.06 63.5 0)
      (effects (font (size 1.524 1.524)) (justify left) hide)
    )
    (property "MPN" "CR0402-FX-2433GLF" (at 101.6 63.5 0)
      (effects (font (size 1.524 1.524)) (justify left) hide)
    )
    (property "Val" "243k" (at 105.41 67.31 90)
      (effects (font (size 1.27 1.27)))
    )
    (property "License" "Apache-2.0" (at 134.62 48.26 0)
      (effects (font (size 1.27 1.27) (thickness 0.15)) (justify left bottom) hide)
    )
    (property "Author" "Antmicro" (at 137.16 48.26 0)
      (effects (font (size 1.27 1.27) (thickness 0.15)) (justify left bottom) hide)
    )
    (property "Tolerance" "1%" (at 119.38 48.26 0)
      (effects (font (size 1.27 1.27)) (justify left bottom) hide)
    )
    (property "Public" "False" (at 139.7 48.26 0)
      (effects (font (size 1.27 1.27)) (justify left bottom) hide)
    )
    (pin "1")
    (pin "2")
    (instances
      (project "ecp5-dc-scm"
        (path ""
          (reference "R91") (unit 1)
        )
      )
    )
  )

  (symbol (lib_id "antmicropower:GND") (at 116.84 72.39 0) (unit 1)
    (in_bom yes) (on_board yes) (dnp no)
    (property "Reference" "#PWR066" (at 116.84 78.74 0)
      (effects (font (size 1.27 1.27)) hide)
    )
    (property "Value" "GND" (at 116.967 76.7842 0)
      (effects (font (size 1.27 1.27)))
    )
    (property "Footprint" "" (at 116.84 72.39 0)
      (effects (font (size 1.27 1.27)) hide)
    )
    (property "Datasheet" "" (at 116.84 72.39 0)
      (effects (font (size 1.27 1.27)) hide)
    )
    (property "Author" "Antmicro" (at 125.73 80.01 0)
      (effects (font (size 1.27 1.27) (thickness 0.15)) (justify left bottom) hide)
    )
    (property "License" "Apache-2.0" (at 125.73 82.55 0)
      (effects (font (size 1.27 1.27) (thickness 0.15)) (justify left bottom) hide)
    )
    (pin "1")
    (instances
      (project "ecp5-dc-scm"
        (path ""
          (reference "#PWR066") (unit 1)
        )
      )
    )
  )

  (symbol (lib_id "antmicroCapacitors0402:C_4n7_0402") (at 148.59 82.55 270) (mirror x) (unit 1)
    (in_bom yes) (on_board yes) (dnp no)
    (property "Reference" "C102" (at 140.97 78.74 90)
      (effects (font (size 1.524 1.524)) (justify left))
    )
    (property "Value" "C_4n7_0402" (at 144.78 82.55 0)
      (effects (font (size 1.524 1.524)) hide)
    )
    (property "Footprint" "antmicro-footprints:C_0402_1005Metric" (at 153.67 77.47 0)
      (effects (font (size 1.524 1.524)) (justify left) hide)
    )
    (property "Datasheet" "https://product.tdk.com/en/search/capacitor/ceramic/mlcc/info?part_no=CGA2B3X7S2A472K050BB" (at 148.59 82.55 0)
      (effects (font (size 1.27 1.27)) hide)
    )
    (property "Manufacturer" "TDK" (at 158.75 77.47 0)
      (effects (font (size 1.524 1.524)) (justify left) hide)
    )
    (property "MPN" "CGA2B3X7S2A472K050BB" (at 156.21 77.47 0)
      (effects (font (size 1.524 1.524)) (justify left) hide)
    )
    (property "Val" "4n7" (at 142.24 81.28 90)
      (effects (font (size 1.27 1.27)) (justify left))
    )
    (property "License" "Apache-2.0" (at 125.73 62.23 0)
      (effects (font (size 1.27 1.27) (thickness 0.15)) (justify left bottom) hide)
    )
    (property "Author" "Antmicro" (at 123.19 62.23 0)
      (effects (font (size 1.27 1.27) (thickness 0.15)) (justify left bottom) hide)
    )
    (property "Voltage" "" (at 120.65 62.23 0)
      (effects (font (size 1.27 1.27)) (justify left bottom) hide)
    )
    (property "Dielectric" "" (at 118.11 62.23 0)
      (effects (font (size 1.27 1.27)) (justify left bottom) hide)
    )
    (property "Public" "False" (at 115.57 62.23 0)
      (effects (font (size 1.27 1.27)) (justify left bottom) hide)
    )
    (pin "1")
    (pin "2")
    (instances
      (project "ecp5-dc-scm"
        (path ""
          (reference "C102") (unit 1)
        )
      )
    )
  )

  (symbol (lib_id "antmicroCapacitors0402:C_47p_0402") (at 152.4 82.55 270) (mirror x) (unit 1)
    (in_bom yes) (on_board yes) (dnp no)
    (property "Reference" "C104" (at 160.02 78.74 90)
      (effects (font (size 1.524 1.524)) (justify right))
    )
    (property "Value" "C_47p_0402" (at 148.59 82.55 0)
      (effects (font (size 1.524 1.524)) hide)
    )
    (property "Footprint" "antmicro-footprints:C_0402_1005Metric" (at 157.48 77.47 0)
      (effects (font (size 1.524 1.524)) (justify left) hide)
    )
    (property "Datasheet" "https://www.kemet.com/en/us/capacitors/product/C0402C470J5GACTU.html" (at 152.4 82.55 0)
      (effects (font (size 1.27 1.27)) hide)
    )
    (property "Manufacturer" "KEMET" (at 162.56 77.47 0)
      (effects (font (size 1.524 1.524)) (justify left) hide)
    )
    (property "MPN" "C0402C470J5GACTU" (at 160.02 77.47 0)
      (effects (font (size 1.524 1.524)) (justify left) hide)
    )
    (property "Val" "47p" (at 157.48 81.28 90)
      (effects (font (size 1.27 1.27)) (justify right))
    )
    (property "License" "Apache-2.0" (at 129.54 62.23 0)
      (effects (font (size 1.27 1.27) (thickness 0.15)) (justify left bottom) hide)
    )
    (property "Author" "Antmicro" (at 127 62.23 0)
      (effects (font (size 1.27 1.27) (thickness 0.15)) (justify left bottom) hide)
    )
    (property "Voltage" "" (at 124.46 62.23 0)
      (effects (font (size 1.27 1.27)) (justify left bottom) hide)
    )
    (property "Dielectric" "C0G" (at 121.92 62.23 0)
      (effects (font (size 1.27 1.27)) (justify left bottom) hide)
    )
    (property "Public" "False" (at 119.38 62.23 0)
      (effects (font (size 1.27 1.27)) (justify left bottom) hide)
    )
    (pin "1")
    (pin "2")
    (instances
      (project "ecp5-dc-scm"
        (path ""
          (reference "C104") (unit 1)
        )
      )
    )
  )

  (symbol (lib_id "antmicropower:GND") (at 152.4 85.09 0) (mirror y) (unit 1)
    (in_bom yes) (on_board yes) (dnp no)
    (property "Reference" "#PWR067" (at 152.4 91.44 0)
      (effects (font (size 1.27 1.27)) hide)
    )
    (property "Value" "GND" (at 152.273 89.4842 0)
      (effects (font (size 1.27 1.27)))
    )
    (property "Footprint" "" (at 152.4 85.09 0)
      (effects (font (size 1.27 1.27)) hide)
    )
    (property "Datasheet" "" (at 152.4 85.09 0)
      (effects (font (size 1.27 1.27)) hide)
    )
    (property "Author" "Antmicro" (at 143.51 92.71 0)
      (effects (font (size 1.27 1.27) (thickness 0.15)) (justify left bottom) hide)
    )
    (property "License" "Apache-2.0" (at 143.51 95.25 0)
      (effects (font (size 1.27 1.27) (thickness 0.15)) (justify left bottom) hide)
    )
    (pin "1")
    (instances
      (project "ecp5-dc-scm"
        (path ""
          (reference "#PWR067") (unit 1)
        )
      )
    )
  )

  (symbol (lib_id "antmicroResistors0402:R_16k9_0402") (at 148.59 71.12 90) (mirror x) (unit 1)
    (in_bom yes) (on_board yes) (dnp no)
    (property "Reference" "R90" (at 142.24 72.39 90)
      (effects (font (size 1.524 1.524)) (justify right))
    )
    (property "Value" "R_16k9_0402" (at 152.4 71.12 0)
      (effects (font (size 1.524 1.524)) hide)
    )
    (property "Footprint" "antmicro-footprints:R_0402_1005Metric" (at 143.51 76.2 0)
      (effects (font (size 1.524 1.524)) (justify left) hide)
    )
    (property "Datasheet" "https://www.bourns.com/docs/product-datasheets/cr.pdf" (at 148.59 71.12 0)
      (effects (font (size 1.27 1.27)) hide)
    )
    (property "Manufacturer" "Bourns" (at 138.43 76.2 0)
      (effects (font (size 1.524 1.524)) (justify left) hide)
    )
    (property "MPN" "CR0402-FX-1692GLF" (at 140.97 76.2 0)
      (effects (font (size 1.524 1.524)) (justify left) hide)
    )
    (property "Val" "16k9" (at 142.24 74.93 90)
      (effects (font (size 1.27 1.27)) (justify right))
    )
    (property "License" "Apache-2.0" (at 173.99 91.44 0)
      (effects (font (size 1.27 1.27) (thickness 0.15)) (justify left bottom) hide)
    )
    (property "Author" "Antmicro" (at 176.53 91.44 0)
      (effects (font (size 1.27 1.27) (thickness 0.15)) (justify left bottom) hide)
    )
    (property "Tolerance" "1%" (at 158.75 91.44 0)
      (effects (font (size 1.27 1.27)) (justify left bottom) hide)
    )
    (property "Public" "False" (at 179.07 91.44 0)
      (effects (font (size 1.27 1.27)) (justify left bottom) hide)
    )
    (pin "1")
    (pin "2")
    (instances
      (project "ecp5-dc-scm"
        (path ""
          (reference "R90") (unit 1)
        )
      )
    )
  )

  (symbol (lib_id "antmicroCapacitorsmisc:C_47u_1210") (at 198.12 140.97 90) (unit 1)
    (in_bom yes) (on_board yes) (dnp no) (fields_autoplaced)
    (property "Reference" "C109" (at 200.66 137.1536 90)
      (effects (font (size 1.524 1.524)) (justify right))
    )
    (property "Value" "C_47u_1210" (at 201.93 140.97 0)
      (effects (font (size 1.524 1.524)) hide)
    )
    (property "Footprint" "antmicro-footprints:C_1210_3225Metric" (at 193.04 135.89 0)
      (effects (font (size 1.524 1.524)) (justify left) hide)
    )
    (property "Datasheet" "https://www.kemet.com/en/us/capacitors/product/C1210C476K8RACTU.html" (at 198.12 140.97 0)
      (effects (font (size 1.27 1.27)) hide)
    )
    (property "Manufacturer" "KEMET" (at 187.96 135.89 0)
      (effects (font (size 1.524 1.524)) (justify left) hide)
    )
    (property "MPN" "C1210C476K8RACTU" (at 190.5 135.89 0)
      (effects (font (size 1.524 1.524)) (justify left) hide)
    )
    (property "Val" "47u" (at 200.66 139.6936 90)
      (effects (font (size 1.27 1.27)) (justify right))
    )
    (property "License" "Apache-2.0" (at 220.98 120.65 0)
      (effects (font (size 1.27 1.27) (thickness 0.15)) (justify left bottom) hide)
    )
    (property "Author" "Antmicro" (at 223.52 120.65 0)
      (effects (font (size 1.27 1.27) (thickness 0.15)) (justify left bottom) hide)
    )
    (property "Voltage" "" (at 226.06 120.65 0)
      (effects (font (size 1.27 1.27)) (justify left bottom) hide)
    )
    (property "Dielectric" "" (at 228.6 120.65 0)
      (effects (font (size 1.27 1.27)) (justify left bottom) hide)
    )
    (property "Public" "False" (at 231.14 120.65 0)
      (effects (font (size 1.27 1.27)) (justify left bottom) hide)
    )
    (pin "1")
    (pin "2")
    (instances
      (project "ecp5-dc-scm"
        (path ""
          (reference "C109") (unit 1)
        )
      )
    )
  )

  (symbol (lib_id "antmicroCapacitorsmisc:C_10u_0805") (at 80.01 134.62 90) (unit 1)
    (in_bom yes) (on_board yes) (dnp no) (fields_autoplaced)
    (property "Reference" "C97" (at 82.55 130.8036 90)
      (effects (font (size 1.524 1.524)) (justify right))
    )
    (property "Value" "C_10u_0805" (at 83.82 134.62 0)
      (effects (font (size 1.524 1.524)) hide)
    )
    (property "Footprint" "antmicro-footprints:C_0805_2012Metric" (at 74.93 129.54 0)
      (effects (font (size 1.524 1.524)) (justify left) hide)
    )
    (property "Datasheet" "https://www.johansontechnology.com/index.php?option=com_jtiproducts&name=160R15X106KV4E" (at 80.01 134.62 0)
      (effects (font (size 1.27 1.27)) hide)
    )
    (property "Manufacturer" "Johanson Technology" (at 69.85 129.54 0)
      (effects (font (size 1.524 1.524)) (justify left) hide)
    )
    (property "MPN" "160R15X106KV4E" (at 72.39 129.54 0)
      (effects (font (size 1.524 1.524)) (justify left) hide)
    )
    (property "Val" "10u" (at 82.55 133.3436 90)
      (effects (font (size 1.27 1.27)) (justify right))
    )
    (property "License" "Apache-2.0" (at 102.87 114.3 0)
      (effects (font (size 1.27 1.27) (thickness 0.15)) (justify left bottom) hide)
    )
    (property "Author" "Antmicro" (at 105.41 114.3 0)
      (effects (font (size 1.27 1.27) (thickness 0.15)) (justify left bottom) hide)
    )
    (property "Voltage" "" (at 107.95 114.3 0)
      (effects (font (size 1.27 1.27)) (justify left bottom) hide)
    )
    (property "Dielectric" "" (at 110.49 114.3 0)
      (effects (font (size 1.27 1.27)) (justify left bottom) hide)
    )
    (property "Public" "False" (at 113.03 114.3 0)
      (effects (font (size 1.27 1.27)) (justify left bottom) hide)
    )
    (pin "1")
    (pin "2")
    (instances
      (project "ecp5-dc-scm"
        (path ""
          (reference "C97") (unit 1)
        )
      )
    )
  )

  (symbol (lib_id "antmicroCapacitorsmisc:C_10u_0805") (at 73.66 134.62 90) (unit 1)
    (in_bom yes) (on_board yes) (dnp no) (fields_autoplaced)
    (property "Reference" "C96" (at 71.12 130.8036 90)
      (effects (font (size 1.524 1.524)) (justify left))
    )
    (property "Value" "C_10u_0805" (at 77.47 134.62 0)
      (effects (font (size 1.524 1.524)) hide)
    )
    (property "Footprint" "antmicro-footprints:C_0805_2012Metric" (at 68.58 129.54 0)
      (effects (font (size 1.524 1.524)) (justify left) hide)
    )
    (property "Datasheet" "https://www.johansontechnology.com/index.php?option=com_jtiproducts&name=160R15X106KV4E" (at 73.66 134.62 0)
      (effects (font (size 1.27 1.27)) hide)
    )
    (property "Manufacturer" "Johanson Technology" (at 63.5 129.54 0)
      (effects (font (size 1.524 1.524)) (justify left) hide)
    )
    (property "MPN" "160R15X106KV4E" (at 66.04 129.54 0)
      (effects (font (size 1.524 1.524)) (justify left) hide)
    )
    (property "Val" "10u" (at 71.12 133.3436 90)
      (effects (font (size 1.27 1.27)) (justify left))
    )
    (property "License" "Apache-2.0" (at 96.52 114.3 0)
      (effects (font (size 1.27 1.27) (thickness 0.15)) (justify left bottom) hide)
    )
    (property "Author" "Antmicro" (at 99.06 114.3 0)
      (effects (font (size 1.27 1.27) (thickness 0.15)) (justify left bottom) hide)
    )
    (property "Voltage" "" (at 101.6 114.3 0)
      (effects (font (size 1.27 1.27)) (justify left bottom) hide)
    )
    (property "Dielectric" "" (at 104.14 114.3 0)
      (effects (font (size 1.27 1.27)) (justify left bottom) hide)
    )
    (property "Public" "False" (at 106.68 114.3 0)
      (effects (font (size 1.27 1.27)) (justify left bottom) hide)
    )
    (pin "1")
    (pin "2")
    (instances
      (project "ecp5-dc-scm"
        (path ""
          (reference "C96") (unit 1)
        )
      )
    )
  )

  (symbol (lib_id "antmicroCapacitors0402:C_100n_0402") (at 148.59 53.34 0) (unit 1)
    (in_bom yes) (on_board yes) (dnp no)
    (property "Reference" "C105" (at 147.32 54.61 0)
      (effects (font (size 1.524 1.524)))
    )
    (property "Value" "C_100n_0402" (at 148.59 57.15 0)
      (effects (font (size 1.524 1.524)) hide)
    )
    (property "Footprint" "antmicro-footprints:C_0402_1005Metric" (at 153.67 48.26 0)
      (effects (font (size 1.524 1.524)) (justify left) hide)
    )
    (property "Datasheet" "https://www.murata.com/products/productdetail?partno=GRM155R61H104KE14%23" (at 148.59 53.34 0)
      (effects (font (size 1.27 1.27)) hide)
    )
    (property "Manufacturer" "Murata" (at 153.67 43.18 0)
      (effects (font (size 1.524 1.524)) (justify left) hide)
    )
    (property "MPN" "GRM155R61H104KE14D" (at 153.67 45.72 0)
      (effects (font (size 1.524 1.524)) (justify left) hide)
    )
    (property "Val" "100n" (at 154.94 54.61 0)
      (effects (font (size 1.27 1.27)))
    )
    (property "License" "Apache-2.0" (at 168.91 76.2 0)
      (effects (font (size 1.27 1.27) (thickness 0.15)) (justify left bottom) hide)
    )
    (property "Author" "Antmicro" (at 168.91 78.74 0)
      (effects (font (size 1.27 1.27) (thickness 0.15)) (justify left bottom) hide)
    )
    (property "Voltage" "50V" (at 168.91 81.28 0)
      (effects (font (size 1.27 1.27)) (justify left bottom) hide)
    )
    (property "Dielectric" "X5R" (at 168.91 83.82 0)
      (effects (font (size 1.27 1.27)) (justify left bottom) hide)
    )
    (property "Public" "False" (at 168.91 86.36 0)
      (effects (font (size 1.27 1.27)) (justify left bottom) hide)
    )
    (pin "1")
    (pin "2")
    (instances
      (project "ecp5-dc-scm"
        (path ""
          (reference "C105") (unit 1)
        )
      )
    )
  )

  (symbol (lib_id "antmicropower:GND") (at 170.18 85.09 0) (unit 1)
    (in_bom yes) (on_board yes) (dnp no)
    (property "Reference" "#PWR073" (at 170.18 91.44 0)
      (effects (font (size 1.27 1.27)) hide)
    )
    (property "Value" "GND" (at 170.307 89.4842 0)
      (effects (font (size 1.27 1.27)))
    )
    (property "Footprint" "" (at 170.18 85.09 0)
      (effects (font (size 1.27 1.27)) hide)
    )
    (property "Datasheet" "" (at 170.18 85.09 0)
      (effects (font (size 1.27 1.27)) hide)
    )
    (property "Author" "Antmicro" (at 179.07 92.71 0)
      (effects (font (size 1.27 1.27) (thickness 0.15)) (justify left bottom) hide)
    )
    (property "License" "Apache-2.0" (at 179.07 95.25 0)
      (effects (font (size 1.27 1.27) (thickness 0.15)) (justify left bottom) hide)
    )
    (pin "1")
    (instances
      (project "ecp5-dc-scm"
        (path ""
          (reference "#PWR073") (unit 1)
        )
      )
    )
  )

  (symbol (lib_id "antmicropower:GND") (at 158.75 66.04 0) (unit 1)
    (in_bom yes) (on_board yes) (dnp no)
    (property "Reference" "#PWR071" (at 158.75 72.39 0)
      (effects (font (size 1.27 1.27)) hide)
    )
    (property "Value" "GND" (at 158.75 69.85 0)
      (effects (font (size 1.27 1.27)))
    )
    (property "Footprint" "" (at 158.75 66.04 0)
      (effects (font (size 1.27 1.27)) hide)
    )
    (property "Datasheet" "" (at 158.75 66.04 0)
      (effects (font (size 1.27 1.27)) hide)
    )
    (property "Author" "Antmicro" (at 167.64 73.66 0)
      (effects (font (size 1.27 1.27) (thickness 0.15)) (justify left bottom) hide)
    )
    (property "License" "Apache-2.0" (at 167.64 76.2 0)
      (effects (font (size 1.27 1.27) (thickness 0.15)) (justify left bottom) hide)
    )
    (pin "1")
    (instances
      (project "ecp5-dc-scm"
        (path ""
          (reference "#PWR071") (unit 1)
        )
      )
    )
  )

  (symbol (lib_id "antmicroResistors0402:R_10k2_0402") (at 170.18 77.47 270) (unit 1)
    (in_bom yes) (on_board yes) (dnp no)
    (property "Reference" "R97" (at 171.45 78.74 90)
      (effects (font (size 1.524 1.524)) (justify left))
    )
    (property "Value" "R_10k2_0402" (at 166.37 77.47 0)
      (effects (font (size 1.524 1.524)) hide)
    )
    (property "Footprint" "antmicro-footprints:R_0402_1005Metric" (at 175.26 82.55 0)
      (effects (font (size 1.524 1.524)) (justify left) hide)
    )
    (property "Datasheet" "https://www.bourns.com/docs/product-datasheets/cr.pdf" (at 170.18 77.47 0)
      (effects (font (size 1.27 1.27)) hide)
    )
    (property "Manufacturer" "Bourns" (at 180.34 82.55 0)
      (effects (font (size 1.524 1.524)) (justify left) hide)
    )
    (property "MPN" "CR0402-FX-1022GLF" (at 177.8 82.55 0)
      (effects (font (size 1.524 1.524)) (justify left) hide)
    )
    (property "Val" "10k2" (at 171.45 81.28 90)
      (effects (font (size 1.27 1.27)) (justify left))
    )
    (property "License" "Apache-2.0" (at 144.78 97.79 0)
      (effects (font (size 1.27 1.27) (thickness 0.15)) (justify left bottom) hide)
    )
    (property "Author" "Antmicro" (at 142.24 97.79 0)
      (effects (font (size 1.27 1.27) (thickness 0.15)) (justify left bottom) hide)
    )
    (property "Tolerance" "1%" (at 160.02 97.79 0)
      (effects (font (size 1.27 1.27)) (justify left bottom) hide)
    )
    (property "Public" "False" (at 139.7 97.79 0)
      (effects (font (size 1.27 1.27)) (justify left bottom) hide)
    )
    (pin "1")
    (pin "2")
    (instances
      (project "ecp5-dc-scm"
        (path ""
          (reference "R97") (unit 1)
        )
      )
    )
  )

  (symbol (lib_id "antmicroPMICPowerSequencers:LM3881") (at 67.31 223.52 0) (unit 1)
    (in_bom yes) (on_board yes) (dnp no) (fields_autoplaced)
    (property "Reference" "U12" (at 75.565 216.535 0)
      (effects (font (size 1.27 1.27)))
    )
    (property "Value" "LM3881MME_NOPB" (at 75.565 219.075 0)
      (effects (font (size 1.27 1.27)))
    )
    (property "Footprint" "antmicro-footprints:VSSOP-8_3x3mm_P0.65mm" (at 67.31 213.36 0)
      (effects (font (size 1.27 1.27)) (justify left) hide)
    )
    (property "Datasheet" "http://www.ti.com/lit/ds/symlink/lm3881.pdf" (at 67.31 210.82 0)
      (effects (font (size 1.27 1.27)) (justify left) hide)
    )
    (property "Manufacturer" "Texas Instruments" (at 67.31 208.28 0)
      (effects (font (size 1.27 1.27)) (justify left) hide)
    )
    (property "MPN" "LM3881MME/NOPB" (at 76.2 210.82 0)
      (effects (font (size 1.27 1.27)) hide)
    )
    (property "Author" "Antmicro" (at 97.79 241.3 0)
      (effects (font (size 1.27 1.27) (thickness 0.15)) (justify left bottom) hide)
    )
    (property "License" "Apache-2.0" (at 97.79 243.84 0)
      (effects (font (size 1.27 1.27) (thickness 0.15)) (justify left bottom) hide)
    )
    (pin "1")
    (pin "2")
    (pin "3")
    (pin "4")
    (pin "5")
    (pin "6")
    (pin "7")
    (pin "8")
    (instances
      (project "ecp5-dc-scm"
        (path ""
          (reference "U12") (unit 1)
        )
      )
    )
  )

  (symbol (lib_id "antmicropower:GND") (at 40.64 50.8 0) (unit 1)
    (in_bom yes) (on_board yes) (dnp no)
    (property "Reference" "#PWR044" (at 40.64 57.15 0)
      (effects (font (size 1.27 1.27)) hide)
    )
    (property "Value" "GND" (at 40.767 55.1942 0)
      (effects (font (size 1.27 1.27)))
    )
    (property "Footprint" "" (at 40.64 50.8 0)
      (effects (font (size 1.27 1.27)) hide)
    )
    (property "Datasheet" "" (at 40.64 50.8 0)
      (effects (font (size 1.27 1.27)) hide)
    )
    (property "Author" "Antmicro" (at 49.53 58.42 0)
      (effects (font (size 1.27 1.27) (thickness 0.15)) (justify left bottom) hide)
    )
    (property "License" "Apache-2.0" (at 49.53 60.96 0)
      (effects (font (size 1.27 1.27) (thickness 0.15)) (justify left bottom) hide)
    )
    (pin "1")
    (instances
      (project "ecp5-dc-scm"
        (path ""
          (reference "#PWR044") (unit 1)
        )
      )
    )
  )

  (symbol (lib_id "antmicroResistors0402:R_49R9_0402") (at 170.18 55.88 270) (unit 1)
    (in_bom yes) (on_board yes) (dnp no)
    (property "Reference" "R95" (at 171.45 57.15 90)
      (effects (font (size 1.524 1.524)) (justify left))
    )
    (property "Value" "R_49R9_0402" (at 166.37 55.88 0)
      (effects (font (size 1.524 1.524)) hide)
    )
    (property "Footprint" "antmicro-footprints:R_0402_1005Metric" (at 175.26 60.96 0)
      (effects (font (size 1.524 1.524)) (justify left) hide)
    )
    (property "Datasheet" "https://www.bourns.com/docs/product-datasheets/cr.pdf" (at 170.18 55.88 0)
      (effects (font (size 1.27 1.27)) hide)
    )
    (property "Manufacturer" "Bourns" (at 180.34 60.96 0)
      (effects (font (size 1.524 1.524)) (justify left) hide)
    )
    (property "MPN" "CR0402-FX-49R9GLF" (at 177.8 60.96 0)
      (effects (font (size 1.524 1.524)) (justify left) hide)
    )
    (property "Val" "49R9" (at 171.45 59.69 90)
      (effects (font (size 1.27 1.27)) (justify left))
    )
    (property "License" "Apache-2.0" (at 144.78 76.2 0)
      (effects (font (size 1.27 1.27) (thickness 0.15)) (justify left bottom) hide)
    )
    (property "Author" "Antmicro" (at 142.24 76.2 0)
      (effects (font (size 1.27 1.27) (thickness 0.15)) (justify left bottom) hide)
    )
    (property "Tolerance" "1%" (at 160.02 76.2 0)
      (effects (font (size 1.27 1.27)) (justify left bottom) hide)
    )
    (property "Public" "False" (at 139.7 76.2 0)
      (effects (font (size 1.27 1.27)) (justify left bottom) hide)
    )
    (pin "1")
    (pin "2")
    (instances
      (project "ecp5-dc-scm"
        (path ""
          (reference "R95") (unit 1)
        )
      )
    )
  )

  (symbol (lib_id "antmicroResistors0402:R_53k6_0402") (at 170.18 63.5 270) (unit 1)
    (in_bom yes) (on_board yes) (dnp no)
    (property "Reference" "R96" (at 171.45 64.77 90)
      (effects (font (size 1.524 1.524)) (justify left))
    )
    (property "Value" "R_53k6_0402" (at 166.37 63.5 0)
      (effects (font (size 1.524 1.524)) hide)
    )
    (property "Footprint" "antmicro-footprints:R_0402_1005Metric" (at 175.26 68.58 0)
      (effects (font (size 1.524 1.524)) (justify left) hide)
    )
    (property "Datasheet" "https://www.bourns.com/docs/product-datasheets/cr.pdf" (at 170.18 63.5 0)
      (effects (font (size 1.27 1.27)) hide)
    )
    (property "Manufacturer" "Bourns" (at 180.34 68.58 0)
      (effects (font (size 1.524 1.524)) (justify left) hide)
    )
    (property "MPN" "CR0402-FX-5362GLF" (at 177.8 68.58 0)
      (effects (font (size 1.524 1.524)) (justify left) hide)
    )
    (property "Val" "53k6" (at 171.45 67.31 90)
      (effects (font (size 1.27 1.27)) (justify left))
    )
    (property "License" "Apache-2.0" (at 144.78 83.82 0)
      (effects (font (size 1.27 1.27) (thickness 0.15)) (justify left bottom) hide)
    )
    (property "Author" "Antmicro" (at 142.24 83.82 0)
      (effects (font (size 1.27 1.27) (thickness 0.15)) (justify left bottom) hide)
    )
    (property "Tolerance" "1%" (at 160.02 83.82 0)
      (effects (font (size 1.27 1.27)) (justify left bottom) hide)
    )
    (property "Public" "False" (at 139.7 83.82 0)
      (effects (font (size 1.27 1.27)) (justify left bottom) hide)
    )
    (pin "1")
    (pin "2")
    (instances
      (project "ecp5-dc-scm"
        (path ""
          (reference "R96") (unit 1)
        )
      )
    )
  )

  (symbol (lib_id "antmicroFixedInductors:L_7u2_7.9A_WE-PDF-1064") (at 161.29 53.34 0) (unit 1)
    (in_bom yes) (on_board yes) (dnp no)
    (property "Reference" "L2" (at 163.83 50.8 0)
      (effects (font (size 1.524 1.524)))
    )
    (property "Value" "WE_7447798720" (at 163.83 50.8 0)
      (effects (font (size 1.524 1.524)) hide)
    )
    (property "Footprint" "antmicro-footprints:L_WE-PDF-1064" (at 162.56 57.15 0)
      (effects (font (size 1.524 1.524)) hide)
    )
    (property "Datasheet" "https://www.we-online.com/catalog/datasheet/7447798720.pdf" (at 162.687 52.578 0)
      (effects (font (size 1.524 1.524)) hide)
    )
    (property "Manufacturer" "Würth Elektronik" (at 161.29 55.88 0)
      (effects (font (size 1.27 1.27)) hide)
    )
    (property "MPN" "7447798720" (at 160.02 54.61 0)
      (effects (font (size 1.27 1.27)) hide)
    )
    (property "Val" "7u2/7.9A" (at 163.83 55.245 0)
      (effects (font (size 1.27 1.27) (thickness 0.15)))
    )
    (property "ISat" "6 A" (at 175.26 69.85 0)
      (effects (font (size 1.27 1.27)) (justify left) hide)
    )
    (property "IMax" "7.9 A" (at 175.26 73.66 0)
      (effects (font (size 1.27 1.27) (thickness 0.15)) (justify left bottom) hide)
    )
    (property "Size" "10.2x10.2" (at 175.26 76.2 0)
      (effects (font (size 1.27 1.27) (thickness 0.15)) (justify left bottom) hide)
    )
    (property "Author" "Antmicro" (at 175.26 78.74 0)
      (effects (font (size 1.27 1.27) (thickness 0.15)) (justify left bottom) hide)
    )
    (property "License" "Apache-2.0" (at 175.26 81.28 0)
      (effects (font (size 1.27 1.27) (thickness 0.15)) (justify left bottom) hide)
    )
    (property "Public" "False" (at 175.26 83.82 0)
      (effects (font (size 1.27 1.27)) (justify left bottom) hide)
    )
    (pin "1")
    (pin "2")
    (instances
      (project "ecp5-dc-scm"
        (path ""
          (reference "L2") (unit 1)
        )
      )
    )
  )

  (symbol (lib_id "antmicroTestPoints:TP_1206_SMD_RCW-0C") (at 44.45 38.1 270) (mirror x) (unit 1)
    (in_bom yes) (on_board yes) (dnp no) (fields_autoplaced)
    (property "Reference" "TP4" (at 44.45 31.75 90)
      (effects (font (size 1.27 1.27)))
    )
    (property "Value" "RCW-0C" (at 43.18 41.91 0)
      (effects (font (size 1.27 1.27)) (justify right) hide)
    )
    (property "Footprint" "antmicro-footprints:TP_1206_SMD_RCW-0C" (at 49.53 33.02 0)
      (effects (font (size 1.524 1.524)) (justify left) hide)
    )
    (property "Datasheet" "https://www.te.com/commerce/DocumentDelivery/DDEController?Action=srchrtrv&DocNm=1773266&DocType=DS&DocLang=English" (at 52.07 33.02 0)
      (effects (font (size 1.524 1.524)) (justify left) hide)
    )
    (property "MPN" "RCW-0C" (at 57.15 33.02 0)
      (effects (font (size 1.524 1.524)) (justify left) hide)
    )
    (property "Manufacturer" "TE Connectivity" (at 72.39 33.02 0)
      (effects (font (size 1.524 1.524)) (justify left) hide)
    )
    (property "Author" "Antmicro" (at 24.13 20.32 0)
      (effects (font (size 1.27 1.27) (thickness 0.15)) (justify left bottom) hide)
    )
    (property "License" "Apache-2.0" (at 21.59 20.32 0)
      (effects (font (size 1.27 1.27) (thickness 0.15)) (justify left bottom) hide)
    )
    (pin "1")
    (instances
      (project "ecp5-dc-scm"
        (path ""
          (reference "TP4") (unit 1)
        )
      )
    )
  )

  (symbol (lib_id "antmicroTestPoints:TP_1206_SMD_RCW-0C") (at 43.18 40.64 0) (mirror x) (unit 1)
    (in_bom yes) (on_board yes) (dnp no) (fields_autoplaced)
    (property "Reference" "TP5" (at 48.26 40.64 0)
      (effects (font (size 1.27 1.27)) (justify left))
    )
    (property "Value" "RCW-0C" (at 45.72 38.1 90)
      (effects (font (size 1.27 1.27)) hide)
    )
    (property "Footprint" "antmicro-footprints:TP_1206_SMD_RCW-0C" (at 48.26 45.72 0)
      (effects (font (size 1.524 1.524)) (justify left) hide)
    )
    (property "Datasheet" "https://www.te.com/commerce/DocumentDelivery/DDEController?Action=srchrtrv&DocNm=1773266&DocType=DS&DocLang=English" (at 48.26 48.26 0)
      (effects (font (size 1.524 1.524)) (justify left) hide)
    )
    (property "MPN" "RCW-0C" (at 48.26 53.34 0)
      (effects (font (size 1.524 1.524)) (justify left) hide)
    )
    (property "Manufacturer" "TE Connectivity" (at 48.26 68.58 0)
      (effects (font (size 1.524 1.524)) (justify left) hide)
    )
    (property "Author" "Antmicro" (at 60.96 20.32 0)
      (effects (font (size 1.27 1.27) (thickness 0.15)) (justify left bottom) hide)
    )
    (property "License" "Apache-2.0" (at 60.96 17.78 0)
      (effects (font (size 1.27 1.27) (thickness 0.15)) (justify left bottom) hide)
    )
    (pin "1")
    (instances
      (project "ecp5-dc-scm"
        (path ""
          (reference "TP5") (unit 1)
        )
      )
    )
  )

  (symbol (lib_id "antmicroCapacitors0603:C_47u_0603") (at 186.69 60.96 90) (unit 1)
    (in_bom yes) (on_board yes) (dnp no)
    (property "Reference" "C110" (at 184.785 56.515 90)
      (effects (font (size 1.524 1.524)) (justify left))
    )
    (property "Value" "C_47u_0603" (at 190.5 60.96 0)
      (effects (font (size 1.524 1.524)) hide)
    )
    (property "Footprint" "antmicro-footprints:C_0603_1608Metric" (at 181.61 55.88 0)
      (effects (font (size 1.524 1.524)) (justify left) hide)
    )
    (property "Datasheet" "https://www.murata.com/products/productdetail?partno=GRM188R60J476ME15%23" (at 186.69 60.96 0)
      (effects (font (size 1.27 1.27)) hide)
    )
    (property "Manufacturer" "Murata" (at 176.53 55.88 0)
      (effects (font (size 1.524 1.524)) (justify left) hide)
    )
    (property "MPN" "GRM188R60J476ME15D" (at 179.07 55.88 0)
      (effects (font (size 1.524 1.524)) (justify left) hide)
    )
    (property "Val" "47u" (at 184.15 59.6836 90)
      (effects (font (size 1.27 1.27)) (justify left))
    )
    (property "License" "Apache-2.0" (at 209.55 40.64 0)
      (effects (font (size 1.27 1.27) (thickness 0.15)) (justify left bottom) hide)
    )
    (property "Author" "Antmicro" (at 212.09 40.64 0)
      (effects (font (size 1.27 1.27) (thickness 0.15)) (justify left bottom) hide)
    )
    (property "Voltage" "" (at 214.63 40.64 0)
      (effects (font (size 1.27 1.27)) (justify left bottom) hide)
    )
    (property "Dielectric" "" (at 217.17 40.64 0)
      (effects (font (size 1.27 1.27)) (justify left bottom) hide)
    )
    (property "Public" "False" (at 219.71 40.64 0)
      (effects (font (size 1.27 1.27)) (justify left bottom) hide)
    )
    (pin "1")
    (pin "2")
    (instances
      (project "ecp5-dc-scm"
        (path ""
          (reference "C110") (unit 1)
        )
      )
    )
  )

  (symbol (lib_id "antmicroCapacitors0603:C_47u_0603") (at 190.5 60.96 90) (unit 1)
    (in_bom yes) (on_board yes) (dnp no)
    (property "Reference" "C111" (at 191.77 56.515 90)
      (effects (font (size 1.524 1.524)) (justify right))
    )
    (property "Value" "C_47u_0603" (at 194.31 60.96 0)
      (effects (font (size 1.524 1.524)) hide)
    )
    (property "Footprint" "antmicro-footprints:C_0603_1608Metric" (at 185.42 55.88 0)
      (effects (font (size 1.524 1.524)) (justify left) hide)
    )
    (property "Datasheet" "https://www.murata.com/products/productdetail?partno=GRM188R60J476ME15%23" (at 190.5 60.96 0)
      (effects (font (size 1.27 1.27)) hide)
    )
    (property "Manufacturer" "Murata" (at 180.34 55.88 0)
      (effects (font (size 1.524 1.524)) (justify left) hide)
    )
    (property "MPN" "GRM188R60J476ME15D" (at 182.88 55.88 0)
      (effects (font (size 1.524 1.524)) (justify left) hide)
    )
    (property "Val" "47u" (at 191.77 59.69 90)
      (effects (font (size 1.27 1.27)) (justify right))
    )
    (property "License" "Apache-2.0" (at 213.36 40.64 0)
      (effects (font (size 1.27 1.27) (thickness 0.15)) (justify left bottom) hide)
    )
    (property "Author" "Antmicro" (at 215.9 40.64 0)
      (effects (font (size 1.27 1.27) (thickness 0.15)) (justify left bottom) hide)
    )
    (property "Voltage" "" (at 218.44 40.64 0)
      (effects (font (size 1.27 1.27)) (justify left bottom) hide)
    )
    (property "Dielectric" "" (at 220.98 40.64 0)
      (effects (font (size 1.27 1.27)) (justify left bottom) hide)
    )
    (property "Public" "False" (at 223.52 40.64 0)
      (effects (font (size 1.27 1.27)) (justify left bottom) hide)
    )
    (pin "1")
    (pin "2")
    (instances
      (project "ecp5-dc-scm"
        (path ""
          (reference "C111") (unit 1)
        )
      )
    )
  )

  (symbol (lib_id "antmicroCapacitors0603:C_47u_0603") (at 199.39 60.96 90) (unit 1)
    (in_bom yes) (on_board yes) (dnp no)
    (property "Reference" "C112" (at 200.66 56.515 90)
      (effects (font (size 1.524 1.524)) (justify right))
    )
    (property "Value" "C_47u_0603" (at 203.2 60.96 0)
      (effects (font (size 1.524 1.524)) hide)
    )
    (property "Footprint" "antmicro-footprints:C_0603_1608Metric" (at 194.31 55.88 0)
      (effects (font (size 1.524 1.524)) (justify left) hide)
    )
    (property "Datasheet" "https://www.murata.com/products/productdetail?partno=GRM188R60J476ME15%23" (at 199.39 60.96 0)
      (effects (font (size 1.27 1.27)) hide)
    )
    (property "Manufacturer" "Murata" (at 189.23 55.88 0)
      (effects (font (size 1.524 1.524)) (justify left) hide)
    )
    (property "MPN" "GRM188R60J476ME15D" (at 191.77 55.88 0)
      (effects (font (size 1.524 1.524)) (justify left) hide)
    )
    (property "Val" "47u" (at 201.295 59.69 90)
      (effects (font (size 1.27 1.27)) (justify right))
    )
    (property "License" "Apache-2.0" (at 222.25 40.64 0)
      (effects (font (size 1.27 1.27) (thickness 0.15)) (justify left bottom) hide)
    )
    (property "Author" "Antmicro" (at 224.79 40.64 0)
      (effects (font (size 1.27 1.27) (thickness 0.15)) (justify left bottom) hide)
    )
    (property "Voltage" "" (at 227.33 40.64 0)
      (effects (font (size 1.27 1.27)) (justify left bottom) hide)
    )
    (property "Dielectric" "" (at 229.87 40.64 0)
      (effects (font (size 1.27 1.27)) (justify left bottom) hide)
    )
    (property "Public" "False" (at 232.41 40.64 0)
      (effects (font (size 1.27 1.27)) (justify left bottom) hide)
    )
    (pin "1")
    (pin "2")
    (instances
      (project "ecp5-dc-scm"
        (path ""
          (reference "C112") (unit 1)
        )
      )
    )
  )

  (symbol (lib_id "antmicropower:GND") (at 85.09 238.76 0) (unit 1)
    (in_bom yes) (on_board yes) (dnp no)
    (property "Reference" "#PWR061" (at 85.09 245.11 0)
      (effects (font (size 1.27 1.27)) hide)
    )
    (property "Value" "GND" (at 85.217 243.1542 0)
      (effects (font (size 1.27 1.27)))
    )
    (property "Footprint" "" (at 85.09 238.76 0)
      (effects (font (size 1.27 1.27)) hide)
    )
    (property "Datasheet" "" (at 85.09 238.76 0)
      (effects (font (size 1.27 1.27)) hide)
    )
    (property "Author" "Antmicro" (at 93.98 246.38 0)
      (effects (font (size 1.27 1.27) (thickness 0.15)) (justify left bottom) hide)
    )
    (property "License" "Apache-2.0" (at 93.98 248.92 0)
      (effects (font (size 1.27 1.27) (thickness 0.15)) (justify left bottom) hide)
    )
    (pin "1")
    (instances
      (project "ecp5-dc-scm"
        (path ""
          (reference "#PWR061") (unit 1)
        )
      )
    )
  )

  (symbol (lib_id "antmicroCapacitors0402:C_10u_0402") (at 313.69 86.36 270) (unit 1)
    (in_bom yes) (on_board yes) (dnp no) (fields_autoplaced)
    (property "Reference" "C114" (at 311.15 87.6363 90)
      (effects (font (size 1.524 1.524)) (justify right))
    )
    (property "Value" "C_10u_0402" (at 309.88 86.36 0)
      (effects (font (size 1.524 1.524)) hide)
    )
    (property "Footprint" "antmicro-footprints:C_0402_1005Metric" (at 318.77 91.44 0)
      (effects (font (size 1.524 1.524)) (justify left) hide)
    )
    (property "Datasheet" "https://www.yageo.com/en/Chart/Download/pdf/CC0402MRX5R5BB106" (at 313.69 86.36 0)
      (effects (font (size 1.27 1.27)) hide)
    )
    (property "Manufacturer" "YAGEO" (at 323.85 91.44 0)
      (effects (font (size 1.524 1.524)) (justify left) hide)
    )
    (property "MPN" "CC0402MRX5R5BB106" (at 321.31 91.44 0)
      (effects (font (size 1.524 1.524)) (justify left) hide)
    )
    (property "Val" "10u" (at 311.15 90.1763 90)
      (effects (font (size 1.27 1.27)) (justify right))
    )
    (property "License" "Apache-2.0" (at 290.83 106.68 0)
      (effects (font (size 1.27 1.27) (thickness 0.15)) (justify left bottom) hide)
    )
    (property "Author" "Antmicro" (at 288.29 106.68 0)
      (effects (font (size 1.27 1.27) (thickness 0.15)) (justify left bottom) hide)
    )
    (property "Voltage" "" (at 285.75 106.68 0)
      (effects (font (size 1.27 1.27)) (justify left bottom) hide)
    )
    (property "Dielectric" "" (at 283.21 106.68 0)
      (effects (font (size 1.27 1.27)) (justify left bottom) hide)
    )
    (property "Public" "False" (at 280.67 106.68 0)
      (effects (font (size 1.27 1.27)) (justify left bottom) hide)
    )
    (pin "1")
    (pin "2")
    (instances
      (project "ecp5-dc-scm"
        (path ""
          (reference "C114") (unit 1)
        )
      )
    )
  )

  (symbol (lib_id "antmicroDCDCConverters:TPS62823DLCT") (at 328.93 83.82 0) (unit 1)
    (in_bom yes) (on_board yes) (dnp no) (fields_autoplaced)
    (property "Reference" "U17" (at 339.09 76.835 0)
      (effects (font (size 1.27 1.27)))
    )
    (property "Value" "TPS62823DLCT" (at 339.09 79.375 0)
      (effects (font (size 1.27 1.27)))
    )
    (property "Footprint" "antmicro-footprints:QFN-8_2x1.5mm" (at 326.39 88.9 0)
      (effects (font (size 1.27 1.27)) hide)
    )
    (property "Datasheet" "https://www.ti.com/lit/ds/symlink/tps62823.pdf?ts=1685970309606&ref_url=https%253A%252F%252Fwww.ti.com%252Fproduct%252FTPS62823%252Fpart-details%252FTPS62823DLCT" (at 328.93 86.36 0)
      (effects (font (size 1.27 1.27)) hide)
    )
    (property "MPN" "TPS62823DLCT" (at 330.2 64.389 0)
      (effects (font (size 1.27 1.27)) hide)
    )
    (property "Manufacturer" "Texas Instruments" (at 330.2 66.7004 0)
      (effects (font (size 1.27 1.27)) hide)
    )
    (property "Author" "Antmicro" (at 363.22 97.79 0)
      (effects (font (size 1.27 1.27) (thickness 0.15)) (justify left bottom) hide)
    )
    (property "License" "Apache-2.0" (at 363.22 100.33 0)
      (effects (font (size 1.27 1.27) (thickness 0.15)) (justify left bottom) hide)
    )
    (pin "1")
    (pin "2")
    (pin "3")
    (pin "5")
    (pin "6")
    (pin "7")
    (pin "8")
    (pin "4")
    (instances
      (project "ecp5-dc-scm"
        (path ""
          (reference "U17") (unit 1)
        )
      )
    )
  )

  (symbol (lib_id "antmicroCapacitors0402:C_120p_100V_0402") (at 363.22 91.44 90) (unit 1)
    (in_bom yes) (on_board yes) (dnp no)
    (property "Reference" "C118" (at 363.22 86.995 90)
      (effects (font (size 1.524 1.524)) (justify right))
    )
    (property "Value" "C_120p_0402" (at 367.03 91.44 0)
      (effects (font (size 1.524 1.524)) hide)
    )
    (property "Footprint" "antmicro-footprints:C_0402_1005Metric" (at 358.14 86.36 0)
      (effects (font (size 1.524 1.524)) (justify left) hide)
    )
    (property "Datasheet" "https://www.kemet.com/en/us/capacitors/product/C0402C121J5GACTU.html" (at 363.22 91.44 0)
      (effects (font (size 1.27 1.27)) hide)
    )
    (property "Manufacturer" "KEMET" (at 353.06 86.36 0)
      (effects (font (size 1.524 1.524)) (justify left) hide)
    )
    (property "MPN" "C0402C121J5GACTU" (at 355.6 86.36 0)
      (effects (font (size 1.524 1.524)) (justify left) hide)
    )
    (property "Val" "120p" (at 363.855 90.805 90)
      (effects (font (size 1.27 1.27)) (justify right))
    )
    (property "License" "Apache-2.0" (at 386.08 71.12 0)
      (effects (font (size 1.27 1.27) (thickness 0.15)) (justify left bottom) hide)
    )
    (property "Author" "Antmicro" (at 388.62 71.12 0)
      (effects (font (size 1.27 1.27) (thickness 0.15)) (justify left bottom) hide)
    )
    (property "Voltage" "100V" (at 391.16 71.12 0)
      (effects (font (size 1.27 1.27)) (justify left bottom) hide)
    )
    (property "Dielectric" "C0G" (at 393.7 71.12 0)
      (effects (font (size 1.27 1.27)) (justify left bottom) hide)
    )
    (property "Public" "False" (at 396.24 71.12 0)
      (effects (font (size 1.27 1.27)) (justify left bottom) hide)
    )
    (pin "1")
    (pin "2")
    (instances
      (project "ecp5-dc-scm"
        (path ""
          (reference "C118") (unit 1)
        )
      )
    )
  )

  (symbol (lib_id "antmicroResistors0402:R_453k_0402") (at 370.84 87.63 270) (unit 1)
    (in_bom yes) (on_board yes) (dnp no)
    (property "Reference" "R114" (at 372.11 87.63 90)
      (effects (font (size 1.524 1.524)) (justify left))
    )
    (property "Value" "R_453k_0402" (at 367.03 87.63 0)
      (effects (font (size 1.524 1.524)) hide)
    )
    (property "Footprint" "antmicro-footprints:R_0402_1005Metric" (at 375.92 92.71 0)
      (effects (font (size 1.524 1.524)) (justify left) hide)
    )
    (property "Datasheet" "https://www.bourns.com/docs/product-datasheets/cr.pdf" (at 370.84 87.63 0)
      (effects (font (size 1.27 1.27)) hide)
    )
    (property "Manufacturer" "Bourns" (at 381 92.71 0)
      (effects (font (size 1.524 1.524)) (justify left) hide)
    )
    (property "MPN" "CR0402-FX-4533GLF" (at 378.46 92.71 0)
      (effects (font (size 1.524 1.524)) (justify left) hide)
    )
    (property "Val" "453k" (at 372.745 91.44 90)
      (effects (font (size 1.27 1.27)) (justify left))
    )
    (property "License" "Apache-2.0" (at 345.44 107.95 0)
      (effects (font (size 1.27 1.27) (thickness 0.15)) (justify left bottom) hide)
    )
    (property "Author" "Antmicro" (at 342.9 107.95 0)
      (effects (font (size 1.27 1.27) (thickness 0.15)) (justify left bottom) hide)
    )
    (property "Tolerance" "1%" (at 360.68 107.95 0)
      (effects (font (size 1.27 1.27)) (justify left bottom) hide)
    )
    (property "Public" "False" (at 340.36 107.95 0)
      (effects (font (size 1.27 1.27)) (justify left bottom) hide)
    )
    (pin "1")
    (pin "2")
    (instances
      (project "ecp5-dc-scm"
        (path ""
          (reference "R114") (unit 1)
        )
      )
    )
  )

  (symbol (lib_id "antmicroResistors0402:R_100k_0402") (at 370.84 97.79 270) (unit 1)
    (in_bom yes) (on_board yes) (dnp no) (fields_autoplaced)
    (property "Reference" "R115" (at 373.38 99.06 90)
      (effects (font (size 1.524 1.524)) (justify left))
    )
    (property "Value" "R_100k_0402" (at 367.03 97.79 0)
      (effects (font (size 1.524 1.524)) hide)
    )
    (property "Footprint" "antmicro-footprints:R_0402_1005Metric" (at 375.92 102.87 0)
      (effects (font (size 1.524 1.524)) (justify left) hide)
    )
    (property "Datasheet" "https://www.bourns.com/docs/product-datasheets/cr.pdf" (at 370.84 97.79 0)
      (effects (font (size 1.27 1.27)) hide)
    )
    (property "Manufacturer" "Bourns" (at 381 102.87 0)
      (effects (font (size 1.524 1.524)) (justify left) hide)
    )
    (property "MPN" "CR0402-FX-1003GLF" (at 378.46 102.87 0)
      (effects (font (size 1.524 1.524)) (justify left) hide)
    )
    (property "Val" "100k" (at 373.38 101.6 90)
      (effects (font (size 1.27 1.27)) (justify left))
    )
    (property "License" "Apache-2.0" (at 345.44 118.11 0)
      (effects (font (size 1.27 1.27) (thickness 0.15)) (justify left bottom) hide)
    )
    (property "Author" "Antmicro" (at 342.9 118.11 0)
      (effects (font (size 1.27 1.27) (thickness 0.15)) (justify left bottom) hide)
    )
    (property "Tolerance" "1%" (at 360.68 118.11 0)
      (effects (font (size 1.27 1.27)) (justify left bottom) hide)
    )
    (property "Public" "False" (at 340.36 118.11 0)
      (effects (font (size 1.27 1.27)) (justify left bottom) hide)
    )
    (pin "1")
    (pin "2")
    (instances
      (project "ecp5-dc-scm"
        (path ""
          (reference "R115") (unit 1)
        )
      )
    )
  )

  (symbol (lib_id "antmicroCapacitors0402:C_10n_0402") (at 63.5 237.49 90) (unit 1)
    (in_bom yes) (on_board yes) (dnp no)
    (property "Reference" "C95" (at 57.785 233.045 90)
      (effects (font (size 1.524 1.524)) (justify right))
    )
    (property "Value" "C_10n_0402" (at 67.31 237.49 0)
      (effects (font (size 1.524 1.524)) hide)
    )
    (property "Footprint" "antmicro-footprints:C_0402_1005Metric" (at 58.42 232.41 0)
      (effects (font (size 1.524 1.524)) (justify left) hide)
    )
    (property "Datasheet" "https://www.murata.com/products/productdetail?partno=GRM155R71H103KA88%23" (at 63.5 237.49 0)
      (effects (font (size 1.27 1.27)) hide)
    )
    (property "Manufacturer" "Murata" (at 53.34 232.41 0)
      (effects (font (size 1.524 1.524)) (justify left) hide)
    )
    (property "MPN" "GRM155R71H103KA88D" (at 55.88 232.41 0)
      (effects (font (size 1.524 1.524)) (justify left) hide)
    )
    (property "Val" "10n" (at 57.785 236.22 90)
      (effects (font (size 1.27 1.27)) (justify right))
    )
    (property "License" "Apache-2.0" (at 86.36 217.17 0)
      (effects (font (size 1.27 1.27) (thickness 0.15)) (justify left bottom) hide)
    )
    (property "Author" "Antmicro" (at 88.9 217.17 0)
      (effects (font (size 1.27 1.27) (thickness 0.15)) (justify left bottom) hide)
    )
    (property "Voltage" "50V" (at 91.44 217.17 0)
      (effects (font (size 1.27 1.27)) (justify left bottom) hide)
    )
    (property "Dielectric" "X7R" (at 93.98 217.17 0)
      (effects (font (size 1.27 1.27)) (justify left bottom) hide)
    )
    (property "Public" "False" (at 96.52 217.17 0)
      (effects (font (size 1.27 1.27)) (justify left bottom) hide)
    )
    (pin "1")
    (pin "2")
    (instances
      (project "ecp5-dc-scm"
        (path ""
          (reference "C95") (unit 1)
        )
      )
    )
  )

  (symbol (lib_id "antmicroCapacitors0402:C_10u_0402") (at 379.73 96.52 90) (unit 1)
    (in_bom yes) (on_board yes) (dnp no)
    (property "Reference" "C123" (at 379.73 92.075 90)
      (effects (font (size 1.524 1.524)) (justify right))
    )
    (property "Value" "C_10u_0402" (at 383.54 96.52 0)
      (effects (font (size 1.524 1.524)) hide)
    )
    (property "Footprint" "antmicro-footprints:C_0402_1005Metric" (at 374.65 91.44 0)
      (effects (font (size 1.524 1.524)) (justify left) hide)
    )
    (property "Datasheet" "https://www.yageo.com/en/Chart/Download/pdf/CC0402MRX5R5BB106" (at 379.73 96.52 0)
      (effects (font (size 1.27 1.27)) hide)
    )
    (property "Manufacturer" "YAGEO" (at 369.57 91.44 0)
      (effects (font (size 1.524 1.524)) (justify left) hide)
    )
    (property "MPN" "CC0402MRX5R5BB106" (at 372.11 91.44 0)
      (effects (font (size 1.524 1.524)) (justify left) hide)
    )
    (property "Val" "10u" (at 380.365 95.885 90)
      (effects (font (size 1.27 1.27)) (justify right))
    )
    (property "License" "Apache-2.0" (at 402.59 76.2 0)
      (effects (font (size 1.27 1.27) (thickness 0.15)) (justify left bottom) hide)
    )
    (property "Author" "Antmicro" (at 405.13 76.2 0)
      (effects (font (size 1.27 1.27) (thickness 0.15)) (justify left bottom) hide)
    )
    (property "Voltage" "" (at 407.67 76.2 0)
      (effects (font (size 1.27 1.27)) (justify left bottom) hide)
    )
    (property "Dielectric" "" (at 410.21 76.2 0)
      (effects (font (size 1.27 1.27)) (justify left bottom) hide)
    )
    (property "Public" "False" (at 412.75 76.2 0)
      (effects (font (size 1.27 1.27)) (justify left bottom) hide)
    )
    (pin "1")
    (pin "2")
    (instances
      (project "ecp5-dc-scm"
        (path ""
          (reference "C123") (unit 1)
        )
      )
    )
  )

  (symbol (lib_id "antmicroCapacitors0402:C_10u_0402") (at 387.35 96.52 90) (unit 1)
    (in_bom yes) (on_board yes) (dnp no)
    (property "Reference" "C128" (at 387.985 92.075 90)
      (effects (font (size 1.524 1.524)) (justify right))
    )
    (property "Value" "C_10u_0402" (at 391.16 96.52 0)
      (effects (font (size 1.524 1.524)) hide)
    )
    (property "Footprint" "antmicro-footprints:C_0402_1005Metric" (at 382.27 91.44 0)
      (effects (font (size 1.524 1.524)) (justify left) hide)
    )
    (property "Datasheet" "https://www.yageo.com/en/Chart/Download/pdf/CC0402MRX5R5BB106" (at 387.35 96.52 0)
      (effects (font (size 1.27 1.27)) hide)
    )
    (property "Manufacturer" "YAGEO" (at 377.19 91.44 0)
      (effects (font (size 1.524 1.524)) (justify left) hide)
    )
    (property "MPN" "CC0402MRX5R5BB106" (at 379.73 91.44 0)
      (effects (font (size 1.524 1.524)) (justify left) hide)
    )
    (property "Val" "10u" (at 388.62 95.885 90)
      (effects (font (size 1.27 1.27)) (justify right))
    )
    (property "License" "Apache-2.0" (at 410.21 76.2 0)
      (effects (font (size 1.27 1.27) (thickness 0.15)) (justify left bottom) hide)
    )
    (property "Author" "Antmicro" (at 412.75 76.2 0)
      (effects (font (size 1.27 1.27) (thickness 0.15)) (justify left bottom) hide)
    )
    (property "Voltage" "" (at 415.29 76.2 0)
      (effects (font (size 1.27 1.27)) (justify left bottom) hide)
    )
    (property "Dielectric" "" (at 417.83 76.2 0)
      (effects (font (size 1.27 1.27)) (justify left bottom) hide)
    )
    (property "Public" "False" (at 420.37 76.2 0)
      (effects (font (size 1.27 1.27)) (justify left bottom) hide)
    )
    (pin "1")
    (pin "2")
    (instances
      (project "ecp5-dc-scm"
        (path ""
          (reference "C128") (unit 1)
        )
      )
    )
  )

  (symbol (lib_id "antmicropower:GND") (at 63.5 238.76 0) (unit 1)
    (in_bom yes) (on_board yes) (dnp no)
    (property "Reference" "#PWR059" (at 63.5 245.11 0)
      (effects (font (size 1.27 1.27)) hide)
    )
    (property "Value" "GND" (at 63.627 243.1542 0)
      (effects (font (size 1.27 1.27)))
    )
    (property "Footprint" "" (at 63.5 238.76 0)
      (effects (font (size 1.27 1.27)) hide)
    )
    (property "Datasheet" "" (at 63.5 238.76 0)
      (effects (font (size 1.27 1.27)) hide)
    )
    (property "Author" "Antmicro" (at 72.39 246.38 0)
      (effects (font (size 1.27 1.27) (thickness 0.15)) (justify left bottom) hide)
    )
    (property "License" "Apache-2.0" (at 72.39 248.92 0)
      (effects (font (size 1.27 1.27) (thickness 0.15)) (justify left bottom) hide)
    )
    (pin "1")
    (instances
      (project "ecp5-dc-scm"
        (path ""
          (reference "#PWR059") (unit 1)
        )
      )
    )
  )

  (symbol (lib_id "antmicropower:GND") (at 314.96 157.48 0) (unit 1)
    (in_bom yes) (on_board yes) (dnp no)
    (property "Reference" "#PWR086" (at 314.96 163.83 0)
      (effects (font (size 1.27 1.27)) hide)
    )
    (property "Value" "GND" (at 315.087 161.8742 0)
      (effects (font (size 1.27 1.27)))
    )
    (property "Footprint" "" (at 314.96 157.48 0)
      (effects (font (size 1.27 1.27)) hide)
    )
    (property "Datasheet" "" (at 314.96 157.48 0)
      (effects (font (size 1.27 1.27)) hide)
    )
    (property "Author" "Antmicro" (at 323.85 165.1 0)
      (effects (font (size 1.27 1.27) (thickness 0.15)) (justify left bottom) hide)
    )
    (property "License" "Apache-2.0" (at 323.85 167.64 0)
      (effects (font (size 1.27 1.27) (thickness 0.15)) (justify left bottom) hide)
    )
    (pin "1")
    (instances
      (project "ecp5-dc-scm"
        (path ""
          (reference "#PWR086") (unit 1)
        )
      )
    )
  )

  (symbol (lib_id "antmicropower:GND") (at 353.06 158.75 0) (unit 1)
    (in_bom yes) (on_board yes) (dnp no)
    (property "Reference" "#PWR091" (at 353.06 165.1 0)
      (effects (font (size 1.27 1.27)) hide)
    )
    (property "Value" "GND" (at 353.187 163.1442 0)
      (effects (font (size 1.27 1.27)))
    )
    (property "Footprint" "" (at 353.06 158.75 0)
      (effects (font (size 1.27 1.27)) hide)
    )
    (property "Datasheet" "" (at 353.06 158.75 0)
      (effects (font (size 1.27 1.27)) hide)
    )
    (property "Author" "Antmicro" (at 361.95 166.37 0)
      (effects (font (size 1.27 1.27) (thickness 0.15)) (justify left bottom) hide)
    )
    (property "License" "Apache-2.0" (at 361.95 168.91 0)
      (effects (font (size 1.27 1.27) (thickness 0.15)) (justify left bottom) hide)
    )
    (pin "1")
    (instances
      (project "ecp5-dc-scm"
        (path ""
          (reference "#PWR091") (unit 1)
        )
      )
    )
  )

  (symbol (lib_id "antmicroCapacitors0402:C_10u_0402") (at 314.96 139.7 270) (mirror x) (unit 1)
    (in_bom yes) (on_board yes) (dnp no)
    (property "Reference" "C115" (at 312.42 135.8836 90)
      (effects (font (size 1.524 1.524)) (justify right))
    )
    (property "Value" "C_10u_0402" (at 311.15 139.7 0)
      (effects (font (size 1.524 1.524)) hide)
    )
    (property "Footprint" "antmicro-footprints:C_0402_1005Metric" (at 320.04 134.62 0)
      (effects (font (size 1.524 1.524)) (justify left) hide)
    )
    (property "Datasheet" "https://www.yageo.com/en/Chart/Download/pdf/CC0402MRX5R5BB106" (at 314.96 139.7 0)
      (effects (font (size 1.27 1.27)) hide)
    )
    (property "Manufacturer" "YAGEO" (at 325.12 134.62 0)
      (effects (font (size 1.524 1.524)) (justify left) hide)
    )
    (property "MPN" "CC0402MRX5R5BB106" (at 322.58 134.62 0)
      (effects (font (size 1.524 1.524)) (justify left) hide)
    )
    (property "Val" "10u" (at 312.42 138.4236 90)
      (effects (font (size 1.27 1.27)) (justify right))
    )
    (property "License" "Apache-2.0" (at 292.1 119.38 0)
      (effects (font (size 1.27 1.27) (thickness 0.15)) (justify left bottom) hide)
    )
    (property "Author" "Antmicro" (at 289.56 119.38 0)
      (effects (font (size 1.27 1.27) (thickness 0.15)) (justify left bottom) hide)
    )
    (property "Voltage" "" (at 287.02 119.38 0)
      (effects (font (size 1.27 1.27)) (justify left bottom) hide)
    )
    (property "Dielectric" "" (at 284.48 119.38 0)
      (effects (font (size 1.27 1.27)) (justify left bottom) hide)
    )
    (property "Public" "False" (at 281.94 119.38 0)
      (effects (font (size 1.27 1.27)) (justify left bottom) hide)
    )
    (pin "1")
    (pin "2")
    (instances
      (project "ecp5-dc-scm"
        (path ""
          (reference "C115") (unit 1)
        )
      )
    )
  )

  (symbol (lib_id "antmicroDCDCConverters:TPS62823DLCT") (at 330.2 132.08 0) (unit 1)
    (in_bom yes) (on_board yes) (dnp no) (fields_autoplaced)
    (property "Reference" "U18" (at 340.36 125.095 0)
      (effects (font (size 1.27 1.27)))
    )
    (property "Value" "TPS62823DLCT" (at 340.36 127.635 0)
      (effects (font (size 1.27 1.27)))
    )
    (property "Footprint" "antmicro-footprints:QFN-8_2x1.5mm" (at 327.66 137.16 0)
      (effects (font (size 1.27 1.27)) hide)
    )
    (property "Datasheet" "https://www.ti.com/lit/ds/symlink/tps62823.pdf?ts=1685970309606&ref_url=https%253A%252F%252Fwww.ti.com%252Fproduct%252FTPS62823%252Fpart-details%252FTPS62823DLCT" (at 330.2 134.62 0)
      (effects (font (size 1.27 1.27)) hide)
    )
    (property "MPN" "TPS62823DLCT" (at 331.47 112.649 0)
      (effects (font (size 1.27 1.27)) hide)
    )
    (property "Manufacturer" "Texas Instruments" (at 331.47 114.9604 0)
      (effects (font (size 1.27 1.27)) hide)
    )
    (property "Author" "Antmicro" (at 364.49 146.05 0)
      (effects (font (size 1.27 1.27) (thickness 0.15)) (justify left bottom) hide)
    )
    (property "License" "Apache-2.0" (at 364.49 148.59 0)
      (effects (font (size 1.27 1.27) (thickness 0.15)) (justify left bottom) hide)
    )
    (pin "1")
    (pin "2")
    (pin "3")
    (pin "5")
    (pin "6")
    (pin "7")
    (pin "8")
    (pin "4")
    (instances
      (project "ecp5-dc-scm"
        (path ""
          (reference "U18") (unit 1)
        )
      )
    )
  )

  (symbol (lib_id "antmicroCapacitors0402:C_120p_100V_0402") (at 364.49 139.7 90) (unit 1)
    (in_bom yes) (on_board yes) (dnp no)
    (property "Reference" "C119" (at 364.49 135.255 90)
      (effects (font (size 1.524 1.524)) (justify right))
    )
    (property "Value" "C_120p_0402" (at 368.3 139.7 0)
      (effects (font (size 1.524 1.524)) hide)
    )
    (property "Footprint" "antmicro-footprints:C_0402_1005Metric" (at 359.41 134.62 0)
      (effects (font (size 1.524 1.524)) (justify left) hide)
    )
    (property "Datasheet" "https://www.kemet.com/en/us/capacitors/product/C0402C121J5GACTU.html" (at 364.49 139.7 0)
      (effects (font (size 1.27 1.27)) hide)
    )
    (property "Manufacturer" "KEMET" (at 354.33 134.62 0)
      (effects (font (size 1.524 1.524)) (justify left) hide)
    )
    (property "MPN" "C0402C121J5GACTU" (at 356.87 134.62 0)
      (effects (font (size 1.524 1.524)) (justify left) hide)
    )
    (property "Val" "120p" (at 365.125 139.065 90)
      (effects (font (size 1.27 1.27)) (justify right))
    )
    (property "License" "Apache-2.0" (at 387.35 119.38 0)
      (effects (font (size 1.27 1.27) (thickness 0.15)) (justify left bottom) hide)
    )
    (property "Author" "Antmicro" (at 389.89 119.38 0)
      (effects (font (size 1.27 1.27) (thickness 0.15)) (justify left bottom) hide)
    )
    (property "Voltage" "100V" (at 392.43 119.38 0)
      (effects (font (size 1.27 1.27)) (justify left bottom) hide)
    )
    (property "Dielectric" "C0G" (at 394.97 119.38 0)
      (effects (font (size 1.27 1.27)) (justify left bottom) hide)
    )
    (property "Public" "False" (at 397.51 119.38 0)
      (effects (font (size 1.27 1.27)) (justify left bottom) hide)
    )
    (pin "1")
    (pin "2")
    (instances
      (project "ecp5-dc-scm"
        (path ""
          (reference "C119") (unit 1)
        )
      )
    )
  )

  (symbol (lib_id "antmicroResistors0402:R_100k_0402") (at 372.11 146.05 270) (unit 1)
    (in_bom yes) (on_board yes) (dnp no) (fields_autoplaced)
    (property "Reference" "R117" (at 374.65 147.32 90)
      (effects (font (size 1.524 1.524)) (justify left))
    )
    (property "Value" "R_100k_0402" (at 368.3 146.05 0)
      (effects (font (size 1.524 1.524)) hide)
    )
    (property "Footprint" "antmicro-footprints:R_0402_1005Metric" (at 377.19 151.13 0)
      (effects (font (size 1.524 1.524)) (justify left) hide)
    )
    (property "Datasheet" "https://www.bourns.com/docs/product-datasheets/cr.pdf" (at 372.11 146.05 0)
      (effects (font (size 1.27 1.27)) hide)
    )
    (property "Manufacturer" "Bourns" (at 382.27 151.13 0)
      (effects (font (size 1.524 1.524)) (justify left) hide)
    )
    (property "MPN" "CR0402-FX-1003GLF" (at 379.73 151.13 0)
      (effects (font (size 1.524 1.524)) (justify left) hide)
    )
    (property "Val" "100k" (at 374.65 149.86 90)
      (effects (font (size 1.27 1.27)) (justify left))
    )
    (property "License" "Apache-2.0" (at 346.71 166.37 0)
      (effects (font (size 1.27 1.27) (thickness 0.15)) (justify left bottom) hide)
    )
    (property "Author" "Antmicro" (at 344.17 166.37 0)
      (effects (font (size 1.27 1.27) (thickness 0.15)) (justify left bottom) hide)
    )
    (property "Tolerance" "1%" (at 361.95 166.37 0)
      (effects (font (size 1.27 1.27)) (justify left bottom) hide)
    )
    (property "Public" "False" (at 341.63 166.37 0)
      (effects (font (size 1.27 1.27)) (justify left bottom) hide)
    )
    (pin "1")
    (pin "2")
    (instances
      (project "ecp5-dc-scm"
        (path ""
          (reference "R117") (unit 1)
        )
      )
    )
  )

  (symbol (lib_id "antmicroCapacitors0402:C_10u_0402") (at 381 144.78 90) (unit 1)
    (in_bom yes) (on_board yes) (dnp no)
    (property "Reference" "C124" (at 381 139.7 90)
      (effects (font (size 1.524 1.524)) (justify right))
    )
    (property "Value" "C_10u_0402" (at 384.81 144.78 0)
      (effects (font (size 1.524 1.524)) hide)
    )
    (property "Footprint" "antmicro-footprints:C_0402_1005Metric" (at 375.92 139.7 0)
      (effects (font (size 1.524 1.524)) (justify left) hide)
    )
    (property "Datasheet" "https://www.yageo.com/en/Chart/Download/pdf/CC0402MRX5R5BB106" (at 381 144.78 0)
      (effects (font (size 1.27 1.27)) hide)
    )
    (property "Manufacturer" "YAGEO" (at 370.84 139.7 0)
      (effects (font (size 1.524 1.524)) (justify left) hide)
    )
    (property "MPN" "CC0402MRX5R5BB106" (at 373.38 139.7 0)
      (effects (font (size 1.524 1.524)) (justify left) hide)
    )
    (property "Val" "10u" (at 381 144.78 90)
      (effects (font (size 1.27 1.27)) (justify right))
    )
    (property "License" "Apache-2.0" (at 403.86 124.46 0)
      (effects (font (size 1.27 1.27) (thickness 0.15)) (justify left bottom) hide)
    )
    (property "Author" "Antmicro" (at 406.4 124.46 0)
      (effects (font (size 1.27 1.27) (thickness 0.15)) (justify left bottom) hide)
    )
    (property "Voltage" "" (at 408.94 124.46 0)
      (effects (font (size 1.27 1.27)) (justify left bottom) hide)
    )
    (property "Dielectric" "" (at 411.48 124.46 0)
      (effects (font (size 1.27 1.27)) (justify left bottom) hide)
    )
    (property "Public" "False" (at 414.02 124.46 0)
      (effects (font (size 1.27 1.27)) (justify left bottom) hide)
    )
    (pin "1")
    (pin "2")
    (instances
      (project "ecp5-dc-scm"
        (path ""
          (reference "C124") (unit 1)
        )
      )
    )
  )

  (symbol (lib_id "antmicroCapacitors0402:C_10u_0402") (at 388.62 144.78 90) (unit 1)
    (in_bom yes) (on_board yes) (dnp no)
    (property "Reference" "C129" (at 389.255 139.065 90)
      (effects (font (size 1.524 1.524)) (justify right))
    )
    (property "Value" "C_10u_0402" (at 392.43 144.78 0)
      (effects (font (size 1.524 1.524)) hide)
    )
    (property "Footprint" "antmicro-footprints:C_0402_1005Metric" (at 383.54 139.7 0)
      (effects (font (size 1.524 1.524)) (justify left) hide)
    )
    (property "Datasheet" "https://www.yageo.com/en/Chart/Download/pdf/CC0402MRX5R5BB106" (at 388.62 144.78 0)
      (effects (font (size 1.27 1.27)) hide)
    )
    (property "Manufacturer" "YAGEO" (at 378.46 139.7 0)
      (effects (font (size 1.524 1.524)) (justify left) hide)
    )
    (property "MPN" "CC0402MRX5R5BB106" (at 381 139.7 0)
      (effects (font (size 1.524 1.524)) (justify left) hide)
    )
    (property "Val" "10u" (at 389.89 144.145 90)
      (effects (font (size 1.27 1.27)) (justify right))
    )
    (property "License" "Apache-2.0" (at 411.48 124.46 0)
      (effects (font (size 1.27 1.27) (thickness 0.15)) (justify left bottom) hide)
    )
    (property "Author" "Antmicro" (at 414.02 124.46 0)
      (effects (font (size 1.27 1.27) (thickness 0.15)) (justify left bottom) hide)
    )
    (property "Voltage" "" (at 416.56 124.46 0)
      (effects (font (size 1.27 1.27)) (justify left bottom) hide)
    )
    (property "Dielectric" "" (at 419.1 124.46 0)
      (effects (font (size 1.27 1.27)) (justify left bottom) hide)
    )
    (property "Public" "False" (at 421.64 124.46 0)
      (effects (font (size 1.27 1.27)) (justify left bottom) hide)
    )
    (pin "1")
    (pin "2")
    (instances
      (project "ecp5-dc-scm"
        (path ""
          (reference "C129") (unit 1)
        )
      )
    )
  )

  (symbol (lib_id "antmicropower:GND") (at 314.96 201.93 0) (unit 1)
    (in_bom yes) (on_board yes) (dnp no)
    (property "Reference" "#PWR087" (at 314.96 208.28 0)
      (effects (font (size 1.27 1.27)) hide)
    )
    (property "Value" "GND" (at 315.087 206.3242 0)
      (effects (font (size 1.27 1.27)))
    )
    (property "Footprint" "" (at 314.96 201.93 0)
      (effects (font (size 1.27 1.27)) hide)
    )
    (property "Datasheet" "" (at 314.96 201.93 0)
      (effects (font (size 1.27 1.27)) hide)
    )
    (property "Author" "Antmicro" (at 323.85 209.55 0)
      (effects (font (size 1.27 1.27) (thickness 0.15)) (justify left bottom) hide)
    )
    (property "License" "Apache-2.0" (at 323.85 212.09 0)
      (effects (font (size 1.27 1.27) (thickness 0.15)) (justify left bottom) hide)
    )
    (pin "1")
    (instances
      (project "ecp5-dc-scm"
        (path ""
          (reference "#PWR087") (unit 1)
        )
      )
    )
  )

  (symbol (lib_id "antmicropower:GND") (at 353.06 203.2 0) (unit 1)
    (in_bom yes) (on_board yes) (dnp no)
    (property "Reference" "#PWR092" (at 353.06 209.55 0)
      (effects (font (size 1.27 1.27)) hide)
    )
    (property "Value" "GND" (at 353.187 207.5942 0)
      (effects (font (size 1.27 1.27)))
    )
    (property "Footprint" "" (at 353.06 203.2 0)
      (effects (font (size 1.27 1.27)) hide)
    )
    (property "Datasheet" "" (at 353.06 203.2 0)
      (effects (font (size 1.27 1.27)) hide)
    )
    (property "Author" "Antmicro" (at 361.95 210.82 0)
      (effects (font (size 1.27 1.27) (thickness 0.15)) (justify left bottom) hide)
    )
    (property "License" "Apache-2.0" (at 361.95 213.36 0)
      (effects (font (size 1.27 1.27) (thickness 0.15)) (justify left bottom) hide)
    )
    (pin "1")
    (instances
      (project "ecp5-dc-scm"
        (path ""
          (reference "#PWR092") (unit 1)
        )
      )
    )
  )

  (symbol (lib_id "antmicroCapacitors0402:C_10u_0402") (at 314.96 186.69 270) (mirror x) (unit 1)
    (in_bom yes) (on_board yes) (dnp no)
    (property "Reference" "C116" (at 312.42 182.8736 90)
      (effects (font (size 1.524 1.524)) (justify right))
    )
    (property "Value" "C_10u_0402" (at 311.15 186.69 0)
      (effects (font (size 1.524 1.524)) hide)
    )
    (property "Footprint" "antmicro-footprints:C_0402_1005Metric" (at 320.04 181.61 0)
      (effects (font (size 1.524 1.524)) (justify left) hide)
    )
    (property "Datasheet" "https://www.yageo.com/en/Chart/Download/pdf/CC0402MRX5R5BB106" (at 314.96 186.69 0)
      (effects (font (size 1.27 1.27)) hide)
    )
    (property "Manufacturer" "YAGEO" (at 325.12 181.61 0)
      (effects (font (size 1.524 1.524)) (justify left) hide)
    )
    (property "MPN" "CC0402MRX5R5BB106" (at 322.58 181.61 0)
      (effects (font (size 1.524 1.524)) (justify left) hide)
    )
    (property "Val" "10u" (at 312.42 185.4136 90)
      (effects (font (size 1.27 1.27)) (justify right))
    )
    (property "License" "Apache-2.0" (at 292.1 166.37 0)
      (effects (font (size 1.27 1.27) (thickness 0.15)) (justify left bottom) hide)
    )
    (property "Author" "Antmicro" (at 289.56 166.37 0)
      (effects (font (size 1.27 1.27) (thickness 0.15)) (justify left bottom) hide)
    )
    (property "Voltage" "" (at 287.02 166.37 0)
      (effects (font (size 1.27 1.27)) (justify left bottom) hide)
    )
    (property "Dielectric" "" (at 284.48 166.37 0)
      (effects (font (size 1.27 1.27)) (justify left bottom) hide)
    )
    (property "Public" "False" (at 281.94 166.37 0)
      (effects (font (size 1.27 1.27)) (justify left bottom) hide)
    )
    (pin "1")
    (pin "2")
    (instances
      (project "ecp5-dc-scm"
        (path ""
          (reference "C116") (unit 1)
        )
      )
    )
  )

  (symbol (lib_id "antmicroDCDCConverters:TPS62823DLCT") (at 330.2 179.07 0) (unit 1)
    (in_bom yes) (on_board yes) (dnp no) (fields_autoplaced)
    (property "Reference" "U19" (at 340.36 172.085 0)
      (effects (font (size 1.27 1.27)))
    )
    (property "Value" "TPS62823DLCT" (at 340.36 174.625 0)
      (effects (font (size 1.27 1.27)))
    )
    (property "Footprint" "antmicro-footprints:QFN-8_2x1.5mm" (at 327.66 184.15 0)
      (effects (font (size 1.27 1.27)) hide)
    )
    (property "Datasheet" "https://www.ti.com/lit/ds/symlink/tps62823.pdf?ts=1685970309606&ref_url=https%253A%252F%252Fwww.ti.com%252Fproduct%252FTPS62823%252Fpart-details%252FTPS62823DLCT" (at 330.2 181.61 0)
      (effects (font (size 1.27 1.27)) hide)
    )
    (property "MPN" "TPS62823DLCT" (at 331.47 159.639 0)
      (effects (font (size 1.27 1.27)) hide)
    )
    (property "Manufacturer" "Texas Instruments" (at 331.47 161.9504 0)
      (effects (font (size 1.27 1.27)) hide)
    )
    (property "Author" "Antmicro" (at 364.49 193.04 0)
      (effects (font (size 1.27 1.27) (thickness 0.15)) (justify left bottom) hide)
    )
    (property "License" "Apache-2.0" (at 364.49 195.58 0)
      (effects (font (size 1.27 1.27) (thickness 0.15)) (justify left bottom) hide)
    )
    (pin "1")
    (pin "2")
    (pin "3")
    (pin "5")
    (pin "6")
    (pin "7")
    (pin "8")
    (pin "4")
    (instances
      (project "ecp5-dc-scm"
        (path ""
          (reference "U19") (unit 1)
        )
      )
    )
  )

  (symbol (lib_id "antmicroCapacitors0402:C_120p_100V_0402") (at 364.49 186.69 90) (unit 1)
    (in_bom yes) (on_board yes) (dnp no)
    (property "Reference" "C120" (at 361.95 186.055 0)
      (effects (font (size 1.524 1.524)) (justify left))
    )
    (property "Value" "C_120p_0402" (at 368.3 186.69 0)
      (effects (font (size 1.524 1.524)) hide)
    )
    (property "Footprint" "antmicro-footprints:C_0402_1005Metric" (at 359.41 181.61 0)
      (effects (font (size 1.524 1.524)) (justify left) hide)
    )
    (property "Datasheet" "https://www.kemet.com/en/us/capacitors/product/C0402C121J5GACTU.html" (at 364.49 186.69 0)
      (effects (font (size 1.27 1.27)) hide)
    )
    (property "Manufacturer" "KEMET" (at 354.33 181.61 0)
      (effects (font (size 1.524 1.524)) (justify left) hide)
    )
    (property "MPN" "C0402C121J5GACTU" (at 356.87 181.61 0)
      (effects (font (size 1.524 1.524)) (justify left) hide)
    )
    (property "Val" "120p" (at 367.03 186.055 0)
      (effects (font (size 1.27 1.27)) (justify left))
    )
    (property "License" "Apache-2.0" (at 387.35 166.37 0)
      (effects (font (size 1.27 1.27) (thickness 0.15)) (justify left bottom) hide)
    )
    (property "Author" "Antmicro" (at 389.89 166.37 0)
      (effects (font (size 1.27 1.27) (thickness 0.15)) (justify left bottom) hide)
    )
    (property "Voltage" "100V" (at 392.43 166.37 0)
      (effects (font (size 1.27 1.27)) (justify left bottom) hide)
    )
    (property "Dielectric" "C0G" (at 394.97 166.37 0)
      (effects (font (size 1.27 1.27)) (justify left bottom) hide)
    )
    (property "Public" "False" (at 397.51 166.37 0)
      (effects (font (size 1.27 1.27)) (justify left bottom) hide)
    )
    (pin "1")
    (pin "2")
    (instances
      (project "ecp5-dc-scm"
        (path ""
          (reference "C120") (unit 1)
        )
      )
    )
  )

  (symbol (lib_id "antmicroResistors0402:R_100k_0402") (at 372.11 191.77 270) (unit 1)
    (in_bom yes) (on_board yes) (dnp no) (fields_autoplaced)
    (property "Reference" "R119" (at 369.57 193.04 90)
      (effects (font (size 1.524 1.524)) (justify right))
    )
    (property "Value" "R_100k_0402" (at 368.3 191.77 0)
      (effects (font (size 1.524 1.524)) hide)
    )
    (property "Footprint" "antmicro-footprints:R_0402_1005Metric" (at 377.19 196.85 0)
      (effects (font (size 1.524 1.524)) (justify left) hide)
    )
    (property "Datasheet" "https://www.bourns.com/docs/product-datasheets/cr.pdf" (at 372.11 191.77 0)
      (effects (font (size 1.27 1.27)) hide)
    )
    (property "Manufacturer" "Bourns" (at 382.27 196.85 0)
      (effects (font (size 1.524 1.524)) (justify left) hide)
    )
    (property "MPN" "CR0402-FX-1003GLF" (at 379.73 196.85 0)
      (effects (font (size 1.524 1.524)) (justify left) hide)
    )
    (property "Val" "100k" (at 369.57 195.58 90)
      (effects (font (size 1.27 1.27)) (justify right))
    )
    (property "License" "Apache-2.0" (at 346.71 212.09 0)
      (effects (font (size 1.27 1.27) (thickness 0.15)) (justify left bottom) hide)
    )
    (property "Author" "Antmicro" (at 344.17 212.09 0)
      (effects (font (size 1.27 1.27) (thickness 0.15)) (justify left bottom) hide)
    )
    (property "Tolerance" "1%" (at 361.95 212.09 0)
      (effects (font (size 1.27 1.27)) (justify left bottom) hide)
    )
    (property "Public" "False" (at 341.63 212.09 0)
      (effects (font (size 1.27 1.27)) (justify left bottom) hide)
    )
    (pin "1")
    (pin "2")
    (instances
      (project "ecp5-dc-scm"
        (path ""
          (reference "R119") (unit 1)
        )
      )
    )
  )

  (symbol (lib_id "antmicroCapacitors0402:C_10u_0402") (at 381 191.77 90) (unit 1)
    (in_bom yes) (on_board yes) (dnp no)
    (property "Reference" "C125" (at 381 187.325 90)
      (effects (font (size 1.524 1.524)) (justify right))
    )
    (property "Value" "C_10u_0402" (at 384.81 191.77 0)
      (effects (font (size 1.524 1.524)) hide)
    )
    (property "Footprint" "antmicro-footprints:C_0402_1005Metric" (at 375.92 186.69 0)
      (effects (font (size 1.524 1.524)) (justify left) hide)
    )
    (property "Datasheet" "https://www.yageo.com/en/Chart/Download/pdf/CC0402MRX5R5BB106" (at 381 191.77 0)
      (effects (font (size 1.27 1.27)) hide)
    )
    (property "Manufacturer" "YAGEO" (at 370.84 186.69 0)
      (effects (font (size 1.524 1.524)) (justify left) hide)
    )
    (property "MPN" "CC0402MRX5R5BB106" (at 373.38 186.69 0)
      (effects (font (size 1.524 1.524)) (justify left) hide)
    )
    (property "Val" "10u" (at 381.635 191.135 90)
      (effects (font (size 1.27 1.27)) (justify right))
    )
    (property "License" "Apache-2.0" (at 403.86 171.45 0)
      (effects (font (size 1.27 1.27) (thickness 0.15)) (justify left bottom) hide)
    )
    (property "Author" "Antmicro" (at 406.4 171.45 0)
      (effects (font (size 1.27 1.27) (thickness 0.15)) (justify left bottom) hide)
    )
    (property "Voltage" "" (at 408.94 171.45 0)
      (effects (font (size 1.27 1.27)) (justify left bottom) hide)
    )
    (property "Dielectric" "" (at 411.48 171.45 0)
      (effects (font (size 1.27 1.27)) (justify left bottom) hide)
    )
    (property "Public" "False" (at 414.02 171.45 0)
      (effects (font (size 1.27 1.27)) (justify left bottom) hide)
    )
    (pin "1")
    (pin "2")
    (instances
      (project "ecp5-dc-scm"
        (path ""
          (reference "C125") (unit 1)
        )
      )
    )
  )

  (symbol (lib_id "antmicroCapacitors0402:C_10u_0402") (at 388.62 191.77 90) (unit 1)
    (in_bom yes) (on_board yes) (dnp no)
    (property "Reference" "C130" (at 389.255 187.325 90)
      (effects (font (size 1.524 1.524)) (justify right))
    )
    (property "Value" "C_10u_0402" (at 392.43 191.77 0)
      (effects (font (size 1.524 1.524)) hide)
    )
    (property "Footprint" "antmicro-footprints:C_0402_1005Metric" (at 383.54 186.69 0)
      (effects (font (size 1.524 1.524)) (justify left) hide)
    )
    (property "Datasheet" "https://www.yageo.com/en/Chart/Download/pdf/CC0402MRX5R5BB106" (at 388.62 191.77 0)
      (effects (font (size 1.27 1.27)) hide)
    )
    (property "Manufacturer" "YAGEO" (at 378.46 186.69 0)
      (effects (font (size 1.524 1.524)) (justify left) hide)
    )
    (property "MPN" "CC0402MRX5R5BB106" (at 381 186.69 0)
      (effects (font (size 1.524 1.524)) (justify left) hide)
    )
    (property "Val" "10u" (at 389.255 191.135 90)
      (effects (font (size 1.27 1.27)) (justify right))
    )
    (property "License" "Apache-2.0" (at 411.48 171.45 0)
      (effects (font (size 1.27 1.27) (thickness 0.15)) (justify left bottom) hide)
    )
    (property "Author" "Antmicro" (at 414.02 171.45 0)
      (effects (font (size 1.27 1.27) (thickness 0.15)) (justify left bottom) hide)
    )
    (property "Voltage" "" (at 416.56 171.45 0)
      (effects (font (size 1.27 1.27)) (justify left bottom) hide)
    )
    (property "Dielectric" "" (at 419.1 171.45 0)
      (effects (font (size 1.27 1.27)) (justify left bottom) hide)
    )
    (property "Public" "False" (at 421.64 171.45 0)
      (effects (font (size 1.27 1.27)) (justify left bottom) hide)
    )
    (pin "1")
    (pin "2")
    (instances
      (project "ecp5-dc-scm"
        (path ""
          (reference "C130") (unit 1)
        )
      )
    )
  )

  (symbol (lib_id "antmicroResistors0402:R_0R_0402") (at 96.52 223.52 0) (unit 1)
    (in_bom yes) (on_board yes) (dnp no)
    (property "Reference" "R137" (at 101.6 216.535 0)
      (effects (font (size 1.524 1.524)))
    )
    (property "Value" "R_0R_0402" (at 96.52 227.33 0)
      (effects (font (size 1.524 1.524)) hide)
    )
    (property "Footprint" "antmicro-footprints:R_0402_1005Metric" (at 101.6 218.44 0)
      (effects (font (size 1.524 1.524)) (justify left) hide)
    )
    (property "Datasheet" "https://industrial.panasonic.com/cdbs/www-data/pdf/RDA0000/AOA0000C301.pdf" (at 96.52 223.52 0)
      (effects (font (size 1.27 1.27)) hide)
    )
    (property "Manufacturer" "Panasonic" (at 101.6 213.36 0)
      (effects (font (size 1.524 1.524)) (justify left) hide)
    )
    (property "MPN" "ERJ2GE0R00X" (at 101.6 215.9 0)
      (effects (font (size 1.524 1.524)) (justify left) hide)
    )
    (property "Val" "0R" (at 106.68 216.535 0)
      (effects (font (size 1.27 1.27)))
    )
    (property "License" "Apache-2.0" (at 116.84 248.92 0)
      (effects (font (size 1.27 1.27) (thickness 0.15)) (justify left bottom) hide)
    )
    (property "Author" "Antmicro" (at 116.84 251.46 0)
      (effects (font (size 1.27 1.27) (thickness 0.15)) (justify left bottom) hide)
    )
    (property "Tolerance" "~" (at 116.84 233.68 0)
      (effects (font (size 1.27 1.27)) (justify left bottom) hide)
    )
    (property "Current" "1A" (at 116.84 254 0)
      (effects (font (size 1.27 1.27) (thickness 0.15)) (justify left bottom) hide)
    )
    (property "Public" "False" (at 116.84 254 0)
      (effects (font (size 1.27 1.27)) (justify left bottom) hide)
    )
    (pin "1")
    (pin "2")
    (instances
      (project "ecp5-dc-scm"
        (path ""
          (reference "R137") (unit 1)
        )
      )
    )
  )

  (symbol (lib_id "antmicroResistors0402:R_0R_0402") (at 96.52 226.06 0) (unit 1)
    (in_bom yes) (on_board yes) (dnp no)
    (property "Reference" "R138" (at 101.6 218.44 0)
      (effects (font (size 1.524 1.524)))
    )
    (property "Value" "R_0R_0402" (at 96.52 229.87 0)
      (effects (font (size 1.524 1.524)) hide)
    )
    (property "Footprint" "antmicro-footprints:R_0402_1005Metric" (at 101.6 220.98 0)
      (effects (font (size 1.524 1.524)) (justify left) hide)
    )
    (property "Datasheet" "https://industrial.panasonic.com/cdbs/www-data/pdf/RDA0000/AOA0000C301.pdf" (at 96.52 226.06 0)
      (effects (font (size 1.27 1.27)) hide)
    )
    (property "Manufacturer" "Panasonic" (at 101.6 215.9 0)
      (effects (font (size 1.524 1.524)) (justify left) hide)
    )
    (property "MPN" "ERJ2GE0R00X" (at 101.6 218.44 0)
      (effects (font (size 1.524 1.524)) (justify left) hide)
    )
    (property "Val" "0R" (at 106.68 218.44 0)
      (effects (font (size 1.27 1.27)))
    )
    (property "License" "Apache-2.0" (at 116.84 251.46 0)
      (effects (font (size 1.27 1.27) (thickness 0.15)) (justify left bottom) hide)
    )
    (property "Author" "Antmicro" (at 116.84 254 0)
      (effects (font (size 1.27 1.27) (thickness 0.15)) (justify left bottom) hide)
    )
    (property "Tolerance" "~" (at 116.84 236.22 0)
      (effects (font (size 1.27 1.27)) (justify left bottom) hide)
    )
    (property "Current" "1A" (at 116.84 256.54 0)
      (effects (font (size 1.27 1.27) (thickness 0.15)) (justify left bottom) hide)
    )
    (property "Public" "False" (at 116.84 256.54 0)
      (effects (font (size 1.27 1.27)) (justify left bottom) hide)
    )
    (pin "1")
    (pin "2")
    (instances
      (project "ecp5-dc-scm"
        (path ""
          (reference "R138") (unit 1)
        )
      )
    )
  )

  (symbol (lib_id "antmicroResistors0402:R_0R_0402") (at 96.52 228.6 0) (unit 1)
    (in_bom yes) (on_board yes) (dnp no)
    (property "Reference" "R139" (at 101.6 220.345 0)
      (effects (font (size 1.524 1.524)))
    )
    (property "Value" "R_0R_0402" (at 96.52 232.41 0)
      (effects (font (size 1.524 1.524)) hide)
    )
    (property "Footprint" "antmicro-footprints:R_0402_1005Metric" (at 101.6 223.52 0)
      (effects (font (size 1.524 1.524)) (justify left) hide)
    )
    (property "Datasheet" "https://industrial.panasonic.com/cdbs/www-data/pdf/RDA0000/AOA0000C301.pdf" (at 96.52 228.6 0)
      (effects (font (size 1.27 1.27)) hide)
    )
    (property "Manufacturer" "Panasonic" (at 101.6 218.44 0)
      (effects (font (size 1.524 1.524)) (justify left) hide)
    )
    (property "MPN" "ERJ2GE0R00X" (at 101.6 220.98 0)
      (effects (font (size 1.524 1.524)) (justify left) hide)
    )
    (property "Val" "0R" (at 106.68 220.345 0)
      (effects (font (size 1.27 1.27)))
    )
    (property "License" "Apache-2.0" (at 116.84 254 0)
      (effects (font (size 1.27 1.27) (thickness 0.15)) (justify left bottom) hide)
    )
    (property "Author" "Antmicro" (at 116.84 256.54 0)
      (effects (font (size 1.27 1.27) (thickness 0.15)) (justify left bottom) hide)
    )
    (property "Tolerance" "~" (at 116.84 238.76 0)
      (effects (font (size 1.27 1.27)) (justify left bottom) hide)
    )
    (property "Current" "1A" (at 116.84 259.08 0)
      (effects (font (size 1.27 1.27) (thickness 0.15)) (justify left bottom) hide)
    )
    (property "Public" "False" (at 116.84 259.08 0)
      (effects (font (size 1.27 1.27)) (justify left bottom) hide)
    )
    (pin "1")
    (pin "2")
    (instances
      (project "ecp5-dc-scm"
        (path ""
          (reference "R139") (unit 1)
        )
      )
    )
  )

  (symbol (lib_id "antmicroResistors0603:R_0R_0603") (at 396.24 36.83 180) (unit 1)
    (in_bom yes) (on_board yes) (dnp no)
    (property "Reference" "R145" (at 393.7 39.37 0)
      (effects (font (size 1.524 1.524)))
    )
    (property "Value" "R_0R_0603" (at 396.24 33.02 0)
      (effects (font (size 1.524 1.524)) hide)
    )
    (property "Footprint" "antmicro-footprints:R_0603_1608Metric" (at 391.16 41.91 0)
      (effects (font (size 1.524 1.524)) (justify left) hide)
    )
    (property "Datasheet" "https://www.bourns.com/docs/product-datasheets/cr.pdf?sfvrsn=574d41f6_14" (at 396.24 36.83 0)
      (effects (font (size 1.27 1.27)) hide)
    )
    (property "Manufacturer" "Bourns" (at 391.16 46.99 0)
      (effects (font (size 1.524 1.524)) (justify left) hide)
    )
    (property "MPN" "CR0603-J/-000ELF" (at 391.16 44.45 0)
      (effects (font (size 1.524 1.524)) (justify left) hide)
    )
    (property "Val" "0R" (at 393.7 41.275 0)
      (effects (font (size 1.27 1.27)))
    )
    (property "License" "Apache-2.0" (at 375.92 11.43 0)
      (effects (font (size 1.27 1.27) (thickness 0.15)) (justify left bottom) hide)
    )
    (property "Author" "Antmicro" (at 375.92 8.89 0)
      (effects (font (size 1.27 1.27) (thickness 0.15)) (justify left bottom) hide)
    )
    (property "Tolerance" "~" (at 375.92 26.67 0)
      (effects (font (size 1.27 1.27)) (justify left bottom) hide)
    )
    (property "Current" "1A" (at 375.92 6.35 0)
      (effects (font (size 1.27 1.27) (thickness 0.15)) (justify left bottom) hide)
    )
    (property "Public" "False" (at 375.92 6.35 0)
      (effects (font (size 1.27 1.27)) (justify left bottom) hide)
    )
    (pin "1")
    (pin "2")
    (instances
      (project "ecp5-dc-scm"
        (path ""
          (reference "R145") (unit 1)
        )
      )
    )
  )

  (symbol (lib_id "antmicroResistors0603:R_0R_0603") (at 394.97 83.82 180) (unit 1)
    (in_bom yes) (on_board yes) (dnp no)
    (property "Reference" "R141" (at 392.43 86.36 0)
      (effects (font (size 1.524 1.524)))
    )
    (property "Value" "R_0R_0603" (at 394.97 80.01 0)
      (effects (font (size 1.524 1.524)) hide)
    )
    (property "Footprint" "antmicro-footprints:R_0603_1608Metric" (at 389.89 88.9 0)
      (effects (font (size 1.524 1.524)) (justify left) hide)
    )
    (property "Datasheet" "https://www.bourns.com/docs/product-datasheets/cr.pdf?sfvrsn=574d41f6_14" (at 394.97 83.82 0)
      (effects (font (size 1.27 1.27)) hide)
    )
    (property "Manufacturer" "Bourns" (at 389.89 93.98 0)
      (effects (font (size 1.524 1.524)) (justify left) hide)
    )
    (property "MPN" "CR0603-J/-000ELF" (at 389.89 91.44 0)
      (effects (font (size 1.524 1.524)) (justify left) hide)
    )
    (property "Val" "0R" (at 392.43 88.9 0)
      (effects (font (size 1.27 1.27)))
    )
    (property "License" "Apache-2.0" (at 374.65 58.42 0)
      (effects (font (size 1.27 1.27) (thickness 0.15)) (justify left bottom) hide)
    )
    (property "Author" "Antmicro" (at 374.65 55.88 0)
      (effects (font (size 1.27 1.27) (thickness 0.15)) (justify left bottom) hide)
    )
    (property "Tolerance" "~" (at 374.65 73.66 0)
      (effects (font (size 1.27 1.27)) (justify left bottom) hide)
    )
    (property "Current" "1A" (at 374.65 53.34 0)
      (effects (font (size 1.27 1.27) (thickness 0.15)) (justify left bottom) hide)
    )
    (property "Public" "False" (at 374.65 53.34 0)
      (effects (font (size 1.27 1.27)) (justify left bottom) hide)
    )
    (pin "1")
    (pin "2")
    (instances
      (project "ecp5-dc-scm"
        (path ""
          (reference "R141") (unit 1)
        )
      )
    )
  )

  (symbol (lib_id "antmicroResistors0603:R_0R_0603") (at 396.24 132.08 180) (unit 1)
    (in_bom yes) (on_board yes) (dnp no)
    (property "Reference" "R142" (at 393.7 134.62 0)
      (effects (font (size 1.524 1.524)))
    )
    (property "Value" "R_0R_0603" (at 396.24 128.27 0)
      (effects (font (size 1.524 1.524)) hide)
    )
    (property "Footprint" "antmicro-footprints:R_0603_1608Metric" (at 391.16 137.16 0)
      (effects (font (size 1.524 1.524)) (justify left) hide)
    )
    (property "Datasheet" "https://www.bourns.com/docs/product-datasheets/cr.pdf?sfvrsn=574d41f6_14" (at 396.24 132.08 0)
      (effects (font (size 1.27 1.27)) hide)
    )
    (property "Manufacturer" "Bourns" (at 391.16 142.24 0)
      (effects (font (size 1.524 1.524)) (justify left) hide)
    )
    (property "MPN" "CR0603-J/-000ELF" (at 391.16 139.7 0)
      (effects (font (size 1.524 1.524)) (justify left) hide)
    )
    (property "Val" "0R" (at 393.7 132.08 0)
      (effects (font (size 1.27 1.27)))
    )
    (property "License" "Apache-2.0" (at 375.92 106.68 0)
      (effects (font (size 1.27 1.27) (thickness 0.15)) (justify left bottom) hide)
    )
    (property "Author" "Antmicro" (at 375.92 104.14 0)
      (effects (font (size 1.27 1.27) (thickness 0.15)) (justify left bottom) hide)
    )
    (property "Tolerance" "~" (at 375.92 121.92 0)
      (effects (font (size 1.27 1.27)) (justify left bottom) hide)
    )
    (property "Current" "1A" (at 375.92 101.6 0)
      (effects (font (size 1.27 1.27) (thickness 0.15)) (justify left bottom) hide)
    )
    (property "Public" "False" (at 375.92 101.6 0)
      (effects (font (size 1.27 1.27)) (justify left bottom) hide)
    )
    (pin "1")
    (pin "2")
    (instances
      (project "ecp5-dc-scm"
        (path ""
          (reference "R142") (unit 1)
        )
      )
    )
  )

  (symbol (lib_id "antmicroResistors0603:R_0R_0603") (at 394.97 179.07 180) (unit 1)
    (in_bom yes) (on_board yes) (dnp no)
    (property "Reference" "R143" (at 392.43 181.61 0)
      (effects (font (size 1.524 1.524)))
    )
    (property "Value" "R_0R_0603" (at 394.97 175.26 0)
      (effects (font (size 1.524 1.524)) hide)
    )
    (property "Footprint" "antmicro-footprints:R_0603_1608Metric" (at 389.89 184.15 0)
      (effects (font (size 1.524 1.524)) (justify left) hide)
    )
    (property "Datasheet" "https://www.bourns.com/docs/product-datasheets/cr.pdf?sfvrsn=574d41f6_14" (at 394.97 179.07 0)
      (effects (font (size 1.27 1.27)) hide)
    )
    (property "Manufacturer" "Bourns" (at 389.89 189.23 0)
      (effects (font (size 1.524 1.524)) (justify left) hide)
    )
    (property "MPN" "CR0603-J/-000ELF" (at 389.89 186.69 0)
      (effects (font (size 1.524 1.524)) (justify left) hide)
    )
    (property "Val" "0R" (at 392.43 184.15 0)
      (effects (font (size 1.27 1.27)))
    )
    (property "License" "Apache-2.0" (at 374.65 153.67 0)
      (effects (font (size 1.27 1.27) (thickness 0.15)) (justify left bottom) hide)
    )
    (property "Author" "Antmicro" (at 374.65 151.13 0)
      (effects (font (size 1.27 1.27) (thickness 0.15)) (justify left bottom) hide)
    )
    (property "Tolerance" "~" (at 374.65 168.91 0)
      (effects (font (size 1.27 1.27)) (justify left bottom) hide)
    )
    (property "Current" "1A" (at 374.65 148.59 0)
      (effects (font (size 1.27 1.27) (thickness 0.15)) (justify left bottom) hide)
    )
    (property "Public" "False" (at 374.65 148.59 0)
      (effects (font (size 1.27 1.27)) (justify left bottom) hide)
    )
    (pin "1")
    (pin "2")
    (instances
      (project "ecp5-dc-scm"
        (path ""
          (reference "R143") (unit 1)
        )
      )
    )
  )

  (symbol (lib_id "antmicroResistors0603:R_0R_0603") (at 396.24 223.52 180) (unit 1)
    (in_bom yes) (on_board yes) (dnp no)
    (property "Reference" "R144" (at 393.7 226.06 0)
      (effects (font (size 1.524 1.524)))
    )
    (property "Value" "R_0R_0603" (at 396.24 219.71 0)
      (effects (font (size 1.524 1.524)) hide)
    )
    (property "Footprint" "antmicro-footprints:R_0603_1608Metric" (at 391.16 228.6 0)
      (effects (font (size 1.524 1.524)) (justify left) hide)
    )
    (property "Datasheet" "https://www.bourns.com/docs/product-datasheets/cr.pdf?sfvrsn=574d41f6_14" (at 396.24 223.52 0)
      (effects (font (size 1.27 1.27)) hide)
    )
    (property "Manufacturer" "Bourns" (at 391.16 233.68 0)
      (effects (font (size 1.524 1.524)) (justify left) hide)
    )
    (property "MPN" "CR0603-J/-000ELF" (at 391.16 231.14 0)
      (effects (font (size 1.524 1.524)) (justify left) hide)
    )
    (property "Val" "0R" (at 393.7 223.52 0)
      (effects (font (size 1.27 1.27)))
    )
    (property "License" "Apache-2.0" (at 375.92 198.12 0)
      (effects (font (size 1.27 1.27) (thickness 0.15)) (justify left bottom) hide)
    )
    (property "Author" "Antmicro" (at 375.92 195.58 0)
      (effects (font (size 1.27 1.27) (thickness 0.15)) (justify left bottom) hide)
    )
    (property "Tolerance" "~" (at 375.92 213.36 0)
      (effects (font (size 1.27 1.27)) (justify left bottom) hide)
    )
    (property "Current" "1A" (at 375.92 193.04 0)
      (effects (font (size 1.27 1.27) (thickness 0.15)) (justify left bottom) hide)
    )
    (property "Public" "False" (at 375.92 193.04 0)
      (effects (font (size 1.27 1.27)) (justify left bottom) hide)
    )
    (pin "1")
    (pin "2")
    (instances
      (project "ecp5-dc-scm"
        (path ""
          (reference "R144") (unit 1)
        )
      )
    )
  )

  (symbol (lib_id "antmicroResistors0603:R_0R_0603") (at 208.28 127 180) (unit 1)
    (in_bom yes) (on_board yes) (dnp no) (fields_autoplaced)
    (property "Reference" "R140" (at 205.74 130.81 0)
      (effects (font (size 1.524 1.524)))
    )
    (property "Value" "R_0R_0603" (at 208.28 123.19 0)
      (effects (font (size 1.524 1.524)) hide)
    )
    (property "Footprint" "antmicro-footprints:R_0603_1608Metric" (at 203.2 132.08 0)
      (effects (font (size 1.524 1.524)) (justify left) hide)
    )
    (property "Datasheet" "https://www.bourns.com/docs/product-datasheets/cr.pdf?sfvrsn=574d41f6_14" (at 208.28 127 0)
      (effects (font (size 1.27 1.27)) hide)
    )
    (property "Manufacturer" "Bourns" (at 203.2 137.16 0)
      (effects (font (size 1.524 1.524)) (justify left) hide)
    )
    (property "MPN" "CR0603-J/-000ELF" (at 203.2 134.62 0)
      (effects (font (size 1.524 1.524)) (justify left) hide)
    )
    (property "Val" "0R" (at 205.74 133.35 0)
      (effects (font (size 1.27 1.27)))
    )
    (property "License" "Apache-2.0" (at 187.96 101.6 0)
      (effects (font (size 1.27 1.27) (thickness 0.15)) (justify left bottom) hide)
    )
    (property "Author" "Antmicro" (at 187.96 99.06 0)
      (effects (font (size 1.27 1.27) (thickness 0.15)) (justify left bottom) hide)
    )
    (property "Tolerance" "~" (at 187.96 116.84 0)
      (effects (font (size 1.27 1.27)) (justify left bottom) hide)
    )
    (property "Current" "1A" (at 187.96 96.52 0)
      (effects (font (size 1.27 1.27) (thickness 0.15)) (justify left bottom) hide)
    )
    (property "Public" "False" (at 187.96 96.52 0)
      (effects (font (size 1.27 1.27)) (justify left bottom) hide)
    )
    (pin "1")
    (pin "2")
    (instances
      (project "ecp5-dc-scm"
        (path ""
          (reference "R140") (unit 1)
        )
      )
    )
  )

  (symbol (lib_id "antmicroFixedInductors:L_470n_6.7A_Vishay-IHLP-1212AE-11") (at 350.52 83.82 0) (unit 1)
    (in_bom yes) (on_board yes) (dnp no) (fields_autoplaced)
    (property "Reference" "L3" (at 353.06 78.74 0)
      (effects (font (size 1.524 1.524)))
    )
    (property "Value" "IHLP1212AEERR47M11" (at 353.06 78.74 0)
      (effects (font (size 1.524 1.524)) hide)
    )
    (property "Footprint" "antmicro-footprints:L_Vishay-IHLP-1212AE" (at 350.52 83.82 0)
      (effects (font (size 1.524 1.524)) hide)
    )
    (property "Datasheet" "https://www.vishay.com/docs/34300/ihlp-1212ae-11.pdf" (at 350.52 83.82 0)
      (effects (font (size 1.524 1.524)) hide)
    )
    (property "Manufacturer" "Vishay" (at 350.52 83.82 0)
      (effects (font (size 1.27 1.27)) hide)
    )
    (property "MPN" "IHLP1212AEERR47M11" (at 350.52 83.82 0)
      (effects (font (size 1.27 1.27)) hide)
    )
    (property "Val" "470n/6.7A" (at 353.06 81.28 0)
      (effects (font (size 1.27 1.27) (thickness 0.15)))
    )
    (property "ISat" "6.7 A" (at 364.49 100.33 0)
      (effects (font (size 1.27 1.27)) (justify left) hide)
    )
    (property "IMax" "6.7 A" (at 364.49 104.14 0)
      (effects (font (size 1.27 1.27) (thickness 0.15)) (justify left bottom) hide)
    )
    (property "Size" "3.0x3.0" (at 364.49 106.68 0)
      (effects (font (size 1.27 1.27) (thickness 0.15)) (justify left bottom) hide)
    )
    (property "Author" "Antmicro" (at 364.49 109.22 0)
      (effects (font (size 1.27 1.27) (thickness 0.15)) (justify left bottom) hide)
    )
    (property "License" "Apache-2.0" (at 364.49 111.76 0)
      (effects (font (size 1.27 1.27) (thickness 0.15)) (justify left bottom) hide)
    )
    (property "Public" "False" (at 364.49 114.3 0)
      (effects (font (size 1.27 1.27)) (justify left bottom) hide)
    )
    (pin "1")
    (pin "2")
    (instances
      (project "ecp5-dc-scm"
        (path ""
          (reference "L3") (unit 1)
        )
      )
    )
  )

  (symbol (lib_id "antmicroFixedInductors:L_470n_6.7A_Vishay-IHLP-1212AE-11") (at 356.87 132.08 0) (unit 1)
    (in_bom yes) (on_board yes) (dnp no) (fields_autoplaced)
    (property "Reference" "L4" (at 359.41 127 0)
      (effects (font (size 1.524 1.524)))
    )
    (property "Value" "IHLP1212AEERR47M11" (at 363.22 129.6924 0)
      (effects (font (size 1.524 1.524)) hide)
    )
    (property "Footprint" "antmicro-footprints:L_Vishay-IHLP-1212AE" (at 356.87 132.08 0)
      (effects (font (size 1.524 1.524)) hide)
    )
    (property "Datasheet" "https://www.vishay.com/docs/34300/ihlp-1212ae-11.pdf" (at 356.87 132.08 0)
      (effects (font (size 1.524 1.524)) hide)
    )
    (property "Manufacturer" "Vishay" (at 356.87 132.08 0)
      (effects (font (size 1.27 1.27)) hide)
    )
    (property "MPN" "IHLP1212AEERR47M11" (at 356.87 132.08 0)
      (effects (font (size 1.27 1.27)) hide)
    )
    (property "Val" "470n/6.7A" (at 359.41 129.54 0)
      (effects (font (size 1.27 1.27) (thickness 0.15)))
    )
    (property "ISat" "6.7 A" (at 370.84 148.59 0)
      (effects (font (size 1.27 1.27)) (justify left) hide)
    )
    (property "IMax" "6.7 A" (at 370.84 152.4 0)
      (effects (font (size 1.27 1.27) (thickness 0.15)) (justify left bottom) hide)
    )
    (property "Size" "3.0x3.0" (at 370.84 154.94 0)
      (effects (font (size 1.27 1.27) (thickness 0.15)) (justify left bottom) hide)
    )
    (property "Author" "Antmicro" (at 370.84 157.48 0)
      (effects (font (size 1.27 1.27) (thickness 0.15)) (justify left bottom) hide)
    )
    (property "License" "Apache-2.0" (at 370.84 160.02 0)
      (effects (font (size 1.27 1.27) (thickness 0.15)) (justify left bottom) hide)
    )
    (property "Public" "False" (at 370.84 162.56 0)
      (effects (font (size 1.27 1.27)) (justify left bottom) hide)
    )
    (pin "1")
    (pin "2")
    (instances
      (project "ecp5-dc-scm"
        (path ""
          (reference "L4") (unit 1)
        )
      )
    )
  )

  (symbol (lib_id "antmicroFixedInductors:L_470n_6.7A_Vishay-IHLP-1212AE-11") (at 351.79 179.07 0) (unit 1)
    (in_bom yes) (on_board yes) (dnp no) (fields_autoplaced)
    (property "Reference" "L5" (at 354.33 173.99 0)
      (effects (font (size 1.524 1.524)))
    )
    (property "Value" "IHLP1212AEERR47M11" (at 351.79 176.3268 0)
      (effects (font (size 1.524 1.524)) hide)
    )
    (property "Footprint" "antmicro-footprints:L_Vishay-IHLP-1212AE" (at 351.79 179.07 0)
      (effects (font (size 1.524 1.524)) hide)
    )
    (property "Datasheet" "https://www.vishay.com/docs/34300/ihlp-1212ae-11.pdf" (at 351.79 179.07 0)
      (effects (font (size 1.524 1.524)) hide)
    )
    (property "Manufacturer" "Vishay" (at 351.79 179.07 0)
      (effects (font (size 1.27 1.27)) hide)
    )
    (property "MPN" "IHLP1212AEERR47M11" (at 351.79 179.07 0)
      (effects (font (size 1.27 1.27)) hide)
    )
    (property "Val" "470n/6.7A" (at 354.33 176.53 0)
      (effects (font (size 1.27 1.27) (thickness 0.15)))
    )
    (property "ISat" "6.7 A" (at 365.76 195.58 0)
      (effects (font (size 1.27 1.27)) (justify left) hide)
    )
    (property "IMax" "6.7 A" (at 365.76 199.39 0)
      (effects (font (size 1.27 1.27) (thickness 0.15)) (justify left bottom) hide)
    )
    (property "Size" "3.0x3.0" (at 365.76 201.93 0)
      (effects (font (size 1.27 1.27) (thickness 0.15)) (justify left bottom) hide)
    )
    (property "Author" "Antmicro" (at 365.76 204.47 0)
      (effects (font (size 1.27 1.27) (thickness 0.15)) (justify left bottom) hide)
    )
    (property "License" "Apache-2.0" (at 365.76 207.01 0)
      (effects (font (size 1.27 1.27) (thickness 0.15)) (justify left bottom) hide)
    )
    (property "Public" "False" (at 365.76 209.55 0)
      (effects (font (size 1.27 1.27)) (justify left bottom) hide)
    )
    (pin "1")
    (pin "2")
    (instances
      (project "ecp5-dc-scm"
        (path ""
          (reference "L5") (unit 1)
        )
      )
    )
  )

  (symbol (lib_id "antmicroResistors0402:R_200k_0402") (at 372.11 134.62 270) (unit 1)
    (in_bom yes) (on_board yes) (dnp no)
    (property "Reference" "R116" (at 373.38 135.255 90)
      (effects (font (size 1.524 1.524)) (justify left))
    )
    (property "Value" "R_200k_0402" (at 368.3 134.62 0)
      (effects (font (size 1.524 1.524)) hide)
    )
    (property "Footprint" "antmicro-footprints:R_0402_1005Metric" (at 377.19 139.7 0)
      (effects (font (size 1.524 1.524)) (justify left) hide)
    )
    (property "Datasheet" "https://www.bourns.com/docs/product-datasheets/cr.pdf" (at 372.11 134.62 0)
      (effects (font (size 1.27 1.27)) hide)
    )
    (property "Manufacturer" "Bourns" (at 382.27 139.7 0)
      (effects (font (size 1.524 1.524)) (justify left) hide)
    )
    (property "MPN" "CR0402-FX-2003GLF" (at 379.73 139.7 0)
      (effects (font (size 1.524 1.524)) (justify left) hide)
    )
    (property "Val" "200k" (at 373.38 139.065 90)
      (effects (font (size 1.27 1.27)) (justify left))
    )
    (property "License" "Apache-2.0" (at 346.71 154.94 0)
      (effects (font (size 1.27 1.27) (thickness 0.15)) (justify left bottom) hide)
    )
    (property "Author" "Antmicro" (at 344.17 154.94 0)
      (effects (font (size 1.27 1.27) (thickness 0.15)) (justify left bottom) hide)
    )
    (property "Tolerance" "1%" (at 361.95 154.94 0)
      (effects (font (size 1.27 1.27)) (justify left bottom) hide)
    )
    (property "Public" "False" (at 341.63 154.94 0)
      (effects (font (size 1.27 1.27)) (justify left bottom) hide)
    )
    (pin "1")
    (pin "2")
    (instances
      (project "ecp5-dc-scm"
        (path ""
          (reference "R116") (unit 1)
        )
      )
    )
  )

  (symbol (lib_id "antmicroResistors0402:R_124k_0402") (at 372.11 181.61 270) (unit 1)
    (in_bom yes) (on_board yes) (dnp no)
    (property "Reference" "R118" (at 373.888 180.467 90)
      (effects (font (size 1.524 1.524)) (justify left))
    )
    (property "Value" "R_124k_0402" (at 368.3 181.61 0)
      (effects (font (size 1.524 1.524)) hide)
    )
    (property "Footprint" "antmicro-footprints:R_0402_1005Metric" (at 377.19 186.69 0)
      (effects (font (size 1.524 1.524)) (justify left) hide)
    )
    (property "Datasheet" "https://www.bourns.com/docs/product-datasheets/cr.pdf" (at 372.11 181.61 0)
      (effects (font (size 1.27 1.27)) hide)
    )
    (property "Manufacturer" "Bourns" (at 382.27 186.69 0)
      (effects (font (size 1.524 1.524)) (justify left) hide)
    )
    (property "MPN" "CR0402-FX-1243GLF" (at 379.73 186.69 0)
      (effects (font (size 1.524 1.524)) (justify left) hide)
    )
    (property "Val" "124k" (at 373.888 182.9562 90)
      (effects (font (size 1.27 1.27)) (justify left))
    )
    (property "License" "Apache-2.0" (at 346.71 201.93 0)
      (effects (font (size 1.27 1.27) (thickness 0.15)) (justify left bottom) hide)
    )
    (property "Author" "Antmicro" (at 344.17 201.93 0)
      (effects (font (size 1.27 1.27) (thickness 0.15)) (justify left bottom) hide)
    )
    (property "Tolerance" "1%" (at 361.95 201.93 0)
      (effects (font (size 1.27 1.27)) (justify left bottom) hide)
    )
    (property "Public" "False" (at 341.63 201.93 0)
      (effects (font (size 1.27 1.27)) (justify left bottom) hide)
    )
    (pin "1")
    (pin "2")
    (instances
      (project "ecp5-dc-scm"
        (path ""
          (reference "R118") (unit 1)
        )
      )
    )
  )

  (symbol (lib_id "antmicropower:GND") (at 314.96 246.38 0) (unit 1)
    (in_bom yes) (on_board yes) (dnp no)
    (property "Reference" "#PWR088" (at 314.96 252.73 0)
      (effects (font (size 1.27 1.27)) hide)
    )
    (property "Value" "GND" (at 315.087 250.7742 0)
      (effects (font (size 1.27 1.27)))
    )
    (property "Footprint" "" (at 314.96 246.38 0)
      (effects (font (size 1.27 1.27)) hide)
    )
    (property "Datasheet" "" (at 314.96 246.38 0)
      (effects (font (size 1.27 1.27)) hide)
    )
    (property "Author" "Antmicro" (at 323.85 254 0)
      (effects (font (size 1.27 1.27) (thickness 0.15)) (justify left bottom) hide)
    )
    (property "License" "Apache-2.0" (at 323.85 256.54 0)
      (effects (font (size 1.27 1.27) (thickness 0.15)) (justify left bottom) hide)
    )
    (pin "1")
    (instances
      (project "ecp5-dc-scm"
        (path ""
          (reference "#PWR088") (unit 1)
        )
      )
    )
  )

  (symbol (lib_id "antmicroCapacitors0402:C_10u_0402") (at 314.96 232.41 270) (mirror x) (unit 1)
    (in_bom yes) (on_board yes) (dnp no)
    (property "Reference" "C117" (at 312.42 228.5936 90)
      (effects (font (size 1.524 1.524)) (justify right))
    )
    (property "Value" "C_10u_0402" (at 311.15 232.41 0)
      (effects (font (size 1.524 1.524)) hide)
    )
    (property "Footprint" "antmicro-footprints:C_0402_1005Metric" (at 320.04 227.33 0)
      (effects (font (size 1.524 1.524)) (justify left) hide)
    )
    (property "Datasheet" "https://www.yageo.com/en/Chart/Download/pdf/CC0402MRX5R5BB106" (at 314.96 232.41 0)
      (effects (font (size 1.27 1.27)) hide)
    )
    (property "Manufacturer" "YAGEO" (at 325.12 227.33 0)
      (effects (font (size 1.524 1.524)) (justify left) hide)
    )
    (property "MPN" "CC0402MRX5R5BB106" (at 322.58 227.33 0)
      (effects (font (size 1.524 1.524)) (justify left) hide)
    )
    (property "Val" "10u" (at 312.42 231.1336 90)
      (effects (font (size 1.27 1.27)) (justify right))
    )
    (property "License" "Apache-2.0" (at 292.1 212.09 0)
      (effects (font (size 1.27 1.27) (thickness 0.15)) (justify left bottom) hide)
    )
    (property "Author" "Antmicro" (at 289.56 212.09 0)
      (effects (font (size 1.27 1.27) (thickness 0.15)) (justify left bottom) hide)
    )
    (property "Voltage" "" (at 287.02 212.09 0)
      (effects (font (size 1.27 1.27)) (justify left bottom) hide)
    )
    (property "Dielectric" "" (at 284.48 212.09 0)
      (effects (font (size 1.27 1.27)) (justify left bottom) hide)
    )
    (property "Public" "False" (at 281.94 212.09 0)
      (effects (font (size 1.27 1.27)) (justify left bottom) hide)
    )
    (pin "1")
    (pin "2")
    (instances
      (project "ecp5-dc-scm"
        (path ""
          (reference "C117") (unit 1)
        )
      )
    )
  )

  (symbol (lib_id "antmicroDCDCConverters:TPS62823DLCT") (at 330.2 223.52 0) (unit 1)
    (in_bom yes) (on_board yes) (dnp no) (fields_autoplaced)
    (property "Reference" "U20" (at 340.36 216.535 0)
      (effects (font (size 1.27 1.27)))
    )
    (property "Value" "TPS62823DLCT" (at 340.36 219.075 0)
      (effects (font (size 1.27 1.27)))
    )
    (property "Footprint" "antmicro-footprints:QFN-8_2x1.5mm" (at 327.66 228.6 0)
      (effects (font (size 1.27 1.27)) hide)
    )
    (property "Datasheet" "https://www.ti.com/lit/ds/symlink/tps62823.pdf?ts=1685970309606&ref_url=https%253A%252F%252Fwww.ti.com%252Fproduct%252FTPS62823%252Fpart-details%252FTPS62823DLCT" (at 330.2 226.06 0)
      (effects (font (size 1.27 1.27)) hide)
    )
    (property "MPN" "TPS62823DLCT" (at 331.47 204.089 0)
      (effects (font (size 1.27 1.27)) hide)
    )
    (property "Manufacturer" "Texas Instruments" (at 331.47 206.4004 0)
      (effects (font (size 1.27 1.27)) hide)
    )
    (property "Author" "Antmicro" (at 364.49 237.49 0)
      (effects (font (size 1.27 1.27) (thickness 0.15)) (justify left bottom) hide)
    )
    (property "License" "Apache-2.0" (at 364.49 240.03 0)
      (effects (font (size 1.27 1.27) (thickness 0.15)) (justify left bottom) hide)
    )
    (pin "1")
    (pin "2")
    (pin "3")
    (pin "5")
    (pin "6")
    (pin "7")
    (pin "8")
    (pin "4")
    (instances
      (project "ecp5-dc-scm"
        (path ""
          (reference "U20") (unit 1)
        )
      )
    )
  )

  (symbol (lib_id "antmicroCapacitors0402:C_120p_100V_0402") (at 364.49 231.14 90) (unit 1)
    (in_bom yes) (on_board yes) (dnp no)
    (property "Reference" "C121" (at 364.49 226.695 90)
      (effects (font (size 1.524 1.524)) (justify right))
    )
    (property "Value" "C_120p_0402" (at 368.3 231.14 0)
      (effects (font (size 1.524 1.524)) hide)
    )
    (property "Footprint" "antmicro-footprints:C_0402_1005Metric" (at 359.41 226.06 0)
      (effects (font (size 1.524 1.524)) (justify left) hide)
    )
    (property "Datasheet" "https://www.kemet.com/en/us/capacitors/product/C0402C121J5GACTU.html" (at 364.49 231.14 0)
      (effects (font (size 1.27 1.27)) hide)
    )
    (property "Manufacturer" "KEMET" (at 354.33 226.06 0)
      (effects (font (size 1.524 1.524)) (justify left) hide)
    )
    (property "MPN" "C0402C121J5GACTU" (at 356.87 226.06 0)
      (effects (font (size 1.524 1.524)) (justify left) hide)
    )
    (property "Val" "120p" (at 365.125 231.14 90)
      (effects (font (size 1.27 1.27)) (justify right))
    )
    (property "License" "Apache-2.0" (at 387.35 210.82 0)
      (effects (font (size 1.27 1.27) (thickness 0.15)) (justify left bottom) hide)
    )
    (property "Author" "Antmicro" (at 389.89 210.82 0)
      (effects (font (size 1.27 1.27) (thickness 0.15)) (justify left bottom) hide)
    )
    (property "Voltage" "100V" (at 392.43 210.82 0)
      (effects (font (size 1.27 1.27)) (justify left bottom) hide)
    )
    (property "Dielectric" "C0G" (at 394.97 210.82 0)
      (effects (font (size 1.27 1.27)) (justify left bottom) hide)
    )
    (property "Public" "False" (at 397.51 210.82 0)
      (effects (font (size 1.27 1.27)) (justify left bottom) hide)
    )
    (pin "1")
    (pin "2")
    (instances
      (project "ecp5-dc-scm"
        (path ""
          (reference "C121") (unit 1)
        )
      )
    )
  )

  (symbol (lib_id "antmicroResistors0402:R_100k_0402") (at 372.11 242.57 90) (unit 1)
    (in_bom yes) (on_board yes) (dnp no) (fields_autoplaced)
    (property "Reference" "R121" (at 374.65 238.76 90)
      (effects (font (size 1.524 1.524)) (justify right))
    )
    (property "Value" "R_100k_0402" (at 375.92 242.57 0)
      (effects (font (size 1.524 1.524)) hide)
    )
    (property "Footprint" "antmicro-footprints:R_0402_1005Metric" (at 367.03 237.49 0)
      (effects (font (size 1.524 1.524)) (justify left) hide)
    )
    (property "Datasheet" "https://www.bourns.com/docs/product-datasheets/cr.pdf" (at 372.11 242.57 0)
      (effects (font (size 1.27 1.27)) hide)
    )
    (property "Manufacturer" "Bourns" (at 361.95 237.49 0)
      (effects (font (size 1.524 1.524)) (justify left) hide)
    )
    (property "MPN" "CR0402-FX-1003GLF" (at 364.49 237.49 0)
      (effects (font (size 1.524 1.524)) (justify left) hide)
    )
    (property "Val" "100k" (at 374.65 241.3 90)
      (effects (font (size 1.27 1.27)) (justify right))
    )
    (property "License" "Apache-2.0" (at 397.51 222.25 0)
      (effects (font (size 1.27 1.27) (thickness 0.15)) (justify left bottom) hide)
    )
    (property "Author" "Antmicro" (at 400.05 222.25 0)
      (effects (font (size 1.27 1.27) (thickness 0.15)) (justify left bottom) hide)
    )
    (property "Tolerance" "1%" (at 382.27 222.25 0)
      (effects (font (size 1.27 1.27)) (justify left bottom) hide)
    )
    (property "Public" "False" (at 402.59 222.25 0)
      (effects (font (size 1.27 1.27)) (justify left bottom) hide)
    )
    (pin "1")
    (pin "2")
    (instances
      (project "ecp5-dc-scm"
        (path ""
          (reference "R121") (unit 1)
        )
      )
    )
  )

  (symbol (lib_id "antmicroCapacitors0402:C_10u_0402") (at 381 236.22 90) (unit 1)
    (in_bom yes) (on_board yes) (dnp no)
    (property "Reference" "C126" (at 381.635 231.14 90)
      (effects (font (size 1.524 1.524)) (justify right))
    )
    (property "Value" "C_10u_0402" (at 384.81 236.22 0)
      (effects (font (size 1.524 1.524)) hide)
    )
    (property "Footprint" "antmicro-footprints:C_0402_1005Metric" (at 375.92 231.14 0)
      (effects (font (size 1.524 1.524)) (justify left) hide)
    )
    (property "Datasheet" "https://www.yageo.com/en/Chart/Download/pdf/CC0402MRX5R5BB106" (at 381 236.22 0)
      (effects (font (size 1.27 1.27)) hide)
    )
    (property "Manufacturer" "YAGEO" (at 370.84 231.14 0)
      (effects (font (size 1.524 1.524)) (justify left) hide)
    )
    (property "MPN" "CC0402MRX5R5BB106" (at 373.38 231.14 0)
      (effects (font (size 1.524 1.524)) (justify left) hide)
    )
    (property "Val" "10u" (at 381.635 235.585 90)
      (effects (font (size 1.27 1.27)) (justify right))
    )
    (property "License" "Apache-2.0" (at 403.86 215.9 0)
      (effects (font (size 1.27 1.27) (thickness 0.15)) (justify left bottom) hide)
    )
    (property "Author" "Antmicro" (at 406.4 215.9 0)
      (effects (font (size 1.27 1.27) (thickness 0.15)) (justify left bottom) hide)
    )
    (property "Voltage" "" (at 408.94 215.9 0)
      (effects (font (size 1.27 1.27)) (justify left bottom) hide)
    )
    (property "Dielectric" "" (at 411.48 215.9 0)
      (effects (font (size 1.27 1.27)) (justify left bottom) hide)
    )
    (property "Public" "False" (at 414.02 215.9 0)
      (effects (font (size 1.27 1.27)) (justify left bottom) hide)
    )
    (pin "1")
    (pin "2")
    (instances
      (project "ecp5-dc-scm"
        (path ""
          (reference "C126") (unit 1)
        )
      )
    )
  )

  (symbol (lib_id "antmicroCapacitors0402:C_10u_0402") (at 388.62 236.22 90) (unit 1)
    (in_bom yes) (on_board yes) (dnp no)
    (property "Reference" "C131" (at 389.255 231.14 90)
      (effects (font (size 1.524 1.524)) (justify right))
    )
    (property "Value" "C_10u_0402" (at 392.43 236.22 0)
      (effects (font (size 1.524 1.524)) hide)
    )
    (property "Footprint" "antmicro-footprints:C_0402_1005Metric" (at 383.54 231.14 0)
      (effects (font (size 1.524 1.524)) (justify left) hide)
    )
    (property "Datasheet" "https://www.yageo.com/en/Chart/Download/pdf/CC0402MRX5R5BB106" (at 388.62 236.22 0)
      (effects (font (size 1.27 1.27)) hide)
    )
    (property "Manufacturer" "YAGEO" (at 378.46 231.14 0)
      (effects (font (size 1.524 1.524)) (justify left) hide)
    )
    (property "MPN" "CC0402MRX5R5BB106" (at 381 231.14 0)
      (effects (font (size 1.524 1.524)) (justify left) hide)
    )
    (property "Val" "10u" (at 389.255 235.585 90)
      (effects (font (size 1.27 1.27)) (justify right))
    )
    (property "License" "Apache-2.0" (at 411.48 215.9 0)
      (effects (font (size 1.27 1.27) (thickness 0.15)) (justify left bottom) hide)
    )
    (property "Author" "Antmicro" (at 414.02 215.9 0)
      (effects (font (size 1.27 1.27) (thickness 0.15)) (justify left bottom) hide)
    )
    (property "Voltage" "" (at 416.56 215.9 0)
      (effects (font (size 1.27 1.27)) (justify left bottom) hide)
    )
    (property "Dielectric" "" (at 419.1 215.9 0)
      (effects (font (size 1.27 1.27)) (justify left bottom) hide)
    )
    (property "Public" "False" (at 421.64 215.9 0)
      (effects (font (size 1.27 1.27)) (justify left bottom) hide)
    )
    (pin "1")
    (pin "2")
    (instances
      (project "ecp5-dc-scm"
        (path ""
          (reference "C131") (unit 1)
        )
      )
    )
  )

  (symbol (lib_id "antmicropower:GND") (at 353.06 247.65 0) (unit 1)
    (in_bom yes) (on_board yes) (dnp no)
    (property "Reference" "#PWR093" (at 353.06 254 0)
      (effects (font (size 1.27 1.27)) hide)
    )
    (property "Value" "GND" (at 353.187 252.0442 0)
      (effects (font (size 1.27 1.27)))
    )
    (property "Footprint" "" (at 353.06 247.65 0)
      (effects (font (size 1.27 1.27)) hide)
    )
    (property "Datasheet" "" (at 353.06 247.65 0)
      (effects (font (size 1.27 1.27)) hide)
    )
    (property "Author" "Antmicro" (at 361.95 255.27 0)
      (effects (font (size 1.27 1.27) (thickness 0.15)) (justify left bottom) hide)
    )
    (property "License" "Apache-2.0" (at 361.95 257.81 0)
      (effects (font (size 1.27 1.27) (thickness 0.15)) (justify left bottom) hide)
    )
    (pin "1")
    (instances
      (project "ecp5-dc-scm"
        (path ""
          (reference "#PWR093") (unit 1)
        )
      )
    )
  )

  (symbol (lib_id "antmicroFixedInductors:L_470n_6.7A_Vishay-IHLP-1212AE-11") (at 351.79 223.52 0) (unit 1)
    (in_bom yes) (on_board yes) (dnp no) (fields_autoplaced)
    (property "Reference" "L6" (at 354.33 218.44 0)
      (effects (font (size 1.524 1.524)))
    )
    (property "Value" "IHLP1212AEERR47M11" (at 358.14 220.98 0)
      (effects (font (size 1.524 1.524)) hide)
    )
    (property "Footprint" "antmicro-footprints:L_Vishay-IHLP-1212AE" (at 351.79 223.52 0)
      (effects (font (size 1.524 1.524)) hide)
    )
    (property "Datasheet" "https://www.vishay.com/docs/34300/ihlp-1212ae-11.pdf" (at 351.79 223.52 0)
      (effects (font (size 1.524 1.524)) hide)
    )
    (property "Manufacturer" "Vishay" (at 351.79 223.52 0)
      (effects (font (size 1.27 1.27)) hide)
    )
    (property "MPN" "IHLP1212AEERR47M11" (at 351.79 223.52 0)
      (effects (font (size 1.27 1.27)) hide)
    )
    (property "Val" "470n/6.7A" (at 354.33 220.98 0)
      (effects (font (size 1.27 1.27) (thickness 0.15)))
    )
    (property "ISat" "6.7 A" (at 365.76 240.03 0)
      (effects (font (size 1.27 1.27)) (justify left) hide)
    )
    (property "IMax" "6.7 A" (at 365.76 243.84 0)
      (effects (font (size 1.27 1.27) (thickness 0.15)) (justify left bottom) hide)
    )
    (property "Size" "3.0x3.0" (at 365.76 246.38 0)
      (effects (font (size 1.27 1.27) (thickness 0.15)) (justify left bottom) hide)
    )
    (property "Author" "Antmicro" (at 365.76 248.92 0)
      (effects (font (size 1.27 1.27) (thickness 0.15)) (justify left bottom) hide)
    )
    (property "License" "Apache-2.0" (at 365.76 251.46 0)
      (effects (font (size 1.27 1.27) (thickness 0.15)) (justify left bottom) hide)
    )
    (property "Public" "False" (at 365.76 254 0)
      (effects (font (size 1.27 1.27)) (justify left bottom) hide)
    )
    (pin "1")
    (pin "2")
    (instances
      (project "ecp5-dc-scm"
        (path ""
          (reference "L6") (unit 1)
        )
      )
    )
  )

  (symbol (lib_name "PDS760_1") (lib_id "antmicroDiodesRectifiersSingle:PDS760") (at 158.75 59.69 270) (unit 1)
    (in_bom yes) (on_board yes) (dnp no)
    (property "Reference" "D6" (at 156.21 60.96 0)
      (effects (font (size 1.27 1.27) (thickness 0.15)) (justify left))
    )
    (property "Value" "PDS760" (at 140.97 82.55 0)
      (effects (font (size 1.27 1.27) (thickness 0.15)) (justify left bottom) hide)
    )
    (property "Footprint" "antmicro-footprints:PowerDI5" (at 148.59 82.55 0)
      (effects (font (size 1.27 1.27) (thickness 0.15)) (justify left bottom) hide)
    )
    (property "Datasheet" "https://www.diodes.com/assets/Datasheets/ds30470.pdf" (at 146.05 82.55 0)
      (effects (font (size 1.27 1.27) (thickness 0.15)) (justify left bottom) hide)
    )
    (property "Manufacturer" "Diodes Incorporated" (at 143.51 82.55 0)
      (effects (font (size 1.27 1.27) (thickness 0.15)) (justify left bottom) hide)
    )
    (property "MPN" "PDS760-13" (at 161.29 57.15 0)
      (effects (font (size 1.27 1.27) (thickness 0.15)) (justify left))
    )
    (property "Author" "Antmicro" (at 138.43 82.55 0)
      (effects (font (size 1.27 1.27) (thickness 0.15)) (justify left bottom) hide)
    )
    (property "License" "Apache-2.0" (at 135.89 82.55 0)
      (effects (font (size 1.27 1.27) (thickness 0.15)) (justify left bottom) hide)
    )
    (pin "2")
    (pin "1")
    (instances
      (project "ecp5-dc-scm"
        (path ""
          (reference "D6") (unit 1)
        )
      )
    )
  )

  (symbol (lib_name "LED_G_0603_LG_L29K-G2J1-24-Z_1") (lib_id "antmicroLEDIndicationDiscrete:LED_G_0603_LG_L29K-G2J1-24-Z") (at 271.78 185.42 180) (unit 1)
    (in_bom yes) (on_board yes) (dnp no)
    (property "Reference" "D7" (at 269.24 182.88 0)
      (effects (font (size 1.27 1.27) (thickness 0.15)))
    )
    (property "Value" "LED_G_0603_LG_L29K-G2J1-24-Z" (at 251.46 177.8 0)
      (effects (font (size 1.27 1.27) (thickness 0.15)) (justify left bottom) hide)
    )
    (property "Footprint" "antmicro-footprints:LED_0603_1608Metric_G" (at 251.46 175.26 0)
      (effects (font (size 1.27 1.27) (thickness 0.15)) (justify left bottom) hide)
    )
    (property "Datasheet" "https://look.ams-osram.com/m/19ee86b3ae0ee95b/original/LG-L29K.pdf" (at 251.46 172.72 0)
      (effects (font (size 1.27 1.27) (thickness 0.15)) (justify left bottom) hide)
    )
    (property "MPN" "LG L29K-G2J1-24-Z" (at 251.46 170.18 0)
      (effects (font (size 1.27 1.27) (thickness 0.15)) (justify left bottom) hide)
    )
    (property "Manufacturer" "OSRAM" (at 251.46 167.64 0)
      (effects (font (size 1.27 1.27) (thickness 0.15)) (justify left bottom) hide)
    )
    (property "Color" "Green" (at 269.24 189.23 0)
      (effects (font (size 1.27 1.27)))
    )
    (property "Author" "Antmicro" (at 251.46 165.1 0)
      (effects (font (size 1.27 1.27) (thickness 0.15)) (justify left bottom) hide)
    )
    (property "License" "Apache-2.0" (at 251.46 162.56 0)
      (effects (font (size 1.27 1.27) (thickness 0.15)) (justify left bottom) hide)
    )
    (pin "1")
    (pin "2")
    (instances
      (project "ecp5-dc-scm"
        (path ""
          (reference "D7") (unit 1)
        )
      )
    )
  )

  (symbol (lib_name "LED_G_0603_LG_L29K-G2J1-24-Z_1") (lib_id "antmicroLEDIndicationDiscrete:LED_G_0603_LG_L29K-G2J1-24-Z") (at 273.05 222.25 180) (unit 1)
    (in_bom yes) (on_board yes) (dnp no)
    (property "Reference" "D10" (at 270.51 219.71 0)
      (effects (font (size 1.27 1.27) (thickness 0.15)))
    )
    (property "Value" "LED_G_0603_LG_L29K-G2J1-24-Z" (at 252.73 214.63 0)
      (effects (font (size 1.27 1.27) (thickness 0.15)) (justify left bottom) hide)
    )
    (property "Footprint" "antmicro-footprints:LED_0603_1608Metric_G" (at 252.73 212.09 0)
      (effects (font (size 1.27 1.27) (thickness 0.15)) (justify left bottom) hide)
    )
    (property "Datasheet" "https://look.ams-osram.com/m/19ee86b3ae0ee95b/original/LG-L29K.pdf" (at 252.73 209.55 0)
      (effects (font (size 1.27 1.27) (thickness 0.15)) (justify left bottom) hide)
    )
    (property "MPN" "LG L29K-G2J1-24-Z" (at 252.73 207.01 0)
      (effects (font (size 1.27 1.27) (thickness 0.15)) (justify left bottom) hide)
    )
    (property "Manufacturer" "OSRAM" (at 252.73 204.47 0)
      (effects (font (size 1.27 1.27) (thickness 0.15)) (justify left bottom) hide)
    )
    (property "Color" "Green" (at 270.51 226.06 0)
      (effects (font (size 1.27 1.27)))
    )
    (property "Author" "Antmicro" (at 252.73 201.93 0)
      (effects (font (size 1.27 1.27) (thickness 0.15)) (justify left bottom) hide)
    )
    (property "License" "Apache-2.0" (at 252.73 199.39 0)
      (effects (font (size 1.27 1.27) (thickness 0.15)) (justify left bottom) hide)
    )
    (pin "1")
    (pin "2")
    (instances
      (project "ecp5-dc-scm"
        (path ""
          (reference "D10") (unit 1)
        )
      )
    )
  )

  (symbol (lib_id "antmicropower:PWR_FLAG") (at 397.51 222.25 0) (unit 1)
    (in_bom yes) (on_board yes) (dnp no)
    (property "Reference" "#FLG014" (at 397.51 220.345 0)
      (effects (font (size 1.27 1.27)) hide)
    )
    (property "Value" "PWR_FLAG" (at 397.51 218.44 0)
      (effects (font (size 1.27 1.27)))
    )
    (property "Footprint" "" (at 397.51 222.25 0)
      (effects (font (size 1.27 1.27)) hide)
    )
    (property "Datasheet" "" (at 397.51 222.25 0)
      (effects (font (size 1.27 1.27)) hide)
    )
    (pin "1")
    (instances
      (project "ecp5-dc-scm"
        (path ""
          (reference "#FLG014") (unit 1)
        )
      )
    )
  )

  (symbol (lib_id "antmicropower:GND") (at 113.03 72.39 0) (unit 1)
    (in_bom yes) (on_board yes) (dnp no)
    (property "Reference" "#PWR023" (at 113.03 78.74 0)
      (effects (font (size 1.27 1.27)) hide)
    )
    (property "Value" "GND" (at 113.157 76.7842 0)
      (effects (font (size 1.27 1.27)))
    )
    (property "Footprint" "" (at 113.03 72.39 0)
      (effects (font (size 1.27 1.27)) hide)
    )
    (property "Datasheet" "" (at 113.03 72.39 0)
      (effects (font (size 1.27 1.27)) hide)
    )
    (property "Author" "Antmicro" (at 121.92 80.01 0)
      (effects (font (size 1.27 1.27) (thickness 0.15)) (justify left bottom) hide)
    )
    (property "License" "Apache-2.0" (at 121.92 82.55 0)
      (effects (font (size 1.27 1.27) (thickness 0.15)) (justify left bottom) hide)
    )
    (pin "1")
    (instances
      (project "ecp5-dc-scm"
        (path ""
          (reference "#PWR023") (unit 1)
        )
      )
    )
  )

  (symbol (lib_id "antmicroPMICVoltageRegulatorsDCDCSwitchingRegulators:LM21212-2") (at 121.92 127 0) (unit 1)
    (in_bom yes) (on_board yes) (dnp no) (fields_autoplaced)
    (property "Reference" "U13" (at 132.08 119.38 0)
      (effects (font (size 1.27 1.27) (thickness 0.15)))
    )
    (property "Value" "LM21212-2" (at 167.64 138.43 0)
      (effects (font (size 1.27 1.27) (thickness 0.15)) (justify left bottom) hide)
    )
    (property "Footprint" "antmicro-footprints:HTSSOP-20_W4.4mm_P0.65mm" (at 167.64 140.97 0)
      (effects (font (size 1.27 1.27) (thickness 0.15)) (justify left bottom) hide)
    )
    (property "Datasheet" "https://www.ti.com/product/LM21212-2" (at 167.64 143.51 0)
      (effects (font (size 1.27 1.27) (thickness 0.15)) (justify left bottom) hide)
    )
    (property "Manufacturer" "Texas Instruments" (at 167.64 146.05 0)
      (effects (font (size 1.27 1.27) (thickness 0.15)) (justify left bottom) hide)
    )
    (property "MPN" "LM21212MH-2/NOPB" (at 132.08 121.92 0)
      (effects (font (size 1.27 1.27) (thickness 0.15)))
    )
    (property "Author" "Antmicro" (at 167.64 148.59 0)
      (effects (font (size 1.27 1.27) (thickness 0.15)) (justify left bottom) hide)
    )
    (property "License" "Apache-2.0" (at 167.64 151.13 0)
      (effects (font (size 1.27 1.27) (thickness 0.15)) (justify left bottom) hide)
    )
    (pin "13")
    (pin "16")
    (pin "15")
    (pin "18")
    (pin "3")
    (pin "19")
    (pin "2")
    (pin "20")
    (pin "9")
    (pin "8")
    (pin "17")
    (pin "5")
    (pin "10")
    (pin "12")
    (pin "11")
    (pin "14")
    (pin "4")
    (pin "21")
    (pin "1")
    (pin "7")
    (pin "6")
    (instances
      (project "ecp5-dc-scm"
        (path ""
          (reference "U13") (unit 1)
        )
      )
    )
  )

  (symbol (lib_id "antmicroTestPoints:TP_1mm_SMD") (at 388.62 177.8 90) (unit 1)
    (in_bom no) (on_board yes) (dnp no)
    (property "Reference" "TP10" (at 391.16 172.72 90)
      (effects (font (size 1.27 1.27) (thickness 0.15)) (justify left))
    )
    (property "Value" "TP_1mm_SMD" (at 396.24 162.56 0)
      (effects (font (size 1.27 1.27) (thickness 0.15)) (justify left bottom) hide)
    )
    (property "Footprint" "antmicro-footprints:TP_SMD_1mm" (at 398.78 162.56 0)
      (effects (font (size 1.27 1.27) (thickness 0.15)) (justify left bottom) hide)
    )
    (property "Datasheet" "" (at 401.32 160.02 0)
      (effects (font (size 1.27 1.27) (thickness 0.15)) (justify left bottom) hide)
    )
    (property "MPN" "" (at 388.62 177.8 0)
      (effects (font (size 1.27 1.27)) hide)
    )
    (property "Manufacturer" "" (at 388.62 177.8 0)
      (effects (font (size 1.27 1.27)) hide)
    )
    (property "Author" "Antmicro" (at 403.86 162.56 0)
      (effects (font (size 1.27 1.27) (thickness 0.15)) (justify left bottom) hide)
    )
    (property "License" "Apache-2.0" (at 406.4 162.56 0)
      (effects (font (size 1.27 1.27) (thickness 0.15)) (justify left bottom) hide)
    )
    (pin "1")
    (instances
      (project "ecp5-dc-scm"
        (path ""
          (reference "TP10") (unit 1)
        )
      )
    )
  )

  (symbol (lib_id "antmicropower:PWR_FLAG") (at 396.24 177.8 0) (unit 1)
    (in_bom yes) (on_board yes) (dnp no)
    (property "Reference" "#FLG013" (at 396.24 175.895 0)
      (effects (font (size 1.27 1.27)) hide)
    )
    (property "Value" "PWR_FLAG" (at 396.24 173.99 0)
      (effects (font (size 1.27 1.27)))
    )
    (property "Footprint" "" (at 396.24 177.8 0)
      (effects (font (size 1.27 1.27)) hide)
    )
    (property "Datasheet" "" (at 396.24 177.8 0)
      (effects (font (size 1.27 1.27)) hide)
    )
    (pin "1")
    (instances
      (project "ecp5-dc-scm"
        (path ""
          (reference "#FLG013") (unit 1)
        )
      )
    )
  )

  (symbol (lib_id "antmicropower:PWR_FLAG") (at 209.55 125.73 0) (unit 1)
    (in_bom yes) (on_board yes) (dnp no)
    (property "Reference" "#FLG05" (at 209.55 123.825 0)
      (effects (font (size 1.27 1.27)) hide)
    )
    (property "Value" "PWR_FLAG" (at 209.55 121.92 0)
      (effects (font (size 1.27 1.27)))
    )
    (property "Footprint" "" (at 209.55 125.73 0)
      (effects (font (size 1.27 1.27)) hide)
    )
    (property "Datasheet" "" (at 209.55 125.73 0)
      (effects (font (size 1.27 1.27)) hide)
    )
    (pin "1")
    (instances
      (project "ecp5-dc-scm"
        (path ""
          (reference "#FLG05") (unit 1)
        )
      )
    )
  )

  (symbol (lib_id "antmicroPMICVoltageRegulatorsLinear:TPS54561QDPRRQ1") (at 119.38 50.8 0) (unit 1)
    (in_bom yes) (on_board yes) (dnp no) (fields_autoplaced)
    (property "Reference" "U15" (at 132.08 44.45 0)
      (effects (font (size 1.27 1.27) (thickness 0.15)))
    )
    (property "Value" "TPS54561QDPRRQ1" (at 157.48 58.42 0)
      (effects (font (size 1.27 1.27) (thickness 0.15)) (justify left bottom) hide)
    )
    (property "Footprint" "antmicro-footprints:WSON-10-1EP_4x4mm_P0.8mm_EP2.6x3mm" (at 157.48 60.96 0)
      (effects (font (size 1.27 1.27) (thickness 0.15)) (justify left bottom) hide)
    )
    (property "Datasheet" "https://www.ti.com/lit/ds/symlink/tps54561-q1.pdf?ts=1678720110394&ref_url=https%253A%252F%252Fwww.google.com%252F" (at 157.48 63.5 0)
      (effects (font (size 1.27 1.27) (thickness 0.15)) (justify left bottom) hide)
    )
    (property "Manufacturer" "Texas Instruments" (at 157.48 66.04 0)
      (effects (font (size 1.27 1.27) (thickness 0.15)) (justify left bottom) hide)
    )
    (property "MPN" "TPS54561QDPRRQ1" (at 132.08 46.99 0)
      (effects (font (size 1.27 1.27) (thickness 0.15)))
    )
    (property "Author" "Antmicro" (at 157.48 68.58 0)
      (effects (font (size 1.27 1.27) (thickness 0.15)) (justify left bottom) hide)
    )
    (property "License" "Apache-2.0" (at 157.48 71.12 0)
      (effects (font (size 1.27 1.27) (thickness 0.15)) (justify left bottom) hide)
    )
    (pin "1")
    (pin "10")
    (pin "7")
    (pin "9")
    (pin "8")
    (pin "11")
    (pin "4")
    (pin "2")
    (pin "3")
    (pin "5")
    (pin "6")
    (instances
      (project "ecp5-dc-scm"
        (path ""
          (reference "U15") (unit 1)
        )
      )
    )
  )

  (symbol (lib_id "antmicroWire2BoardConnectors:Molex_Pico-Lock_1x2_504050-0291") (at 160.02 218.44 0) (unit 1)
    (in_bom yes) (on_board yes) (dnp no) (fields_autoplaced)
    (property "Reference" "J18" (at 166.37 219.71 0)
      (effects (font (size 1.27 1.27) (thickness 0.15)) (justify left))
    )
    (property "Value" "Molex_Pico-Lock_1x2_504050-0291" (at 168.91 220.98 0)
      (effects (font (size 1.27 1.27) (thickness 0.15)) (justify left bottom) hide)
    )
    (property "Footprint" "antmicro-footprints:Conn_Molex_Pico-Lock_1x2_504050-0291" (at 168.91 223.52 0)
      (effects (font (size 1.27 1.27) (thickness 0.15)) (justify left bottom) hide)
    )
    (property "Datasheet" "https://tools.molex.com/pdm_docs/ps/PS-504051-001-001.pdf" (at 168.91 226.06 0)
      (effects (font (size 1.27 1.27) (thickness 0.15)) (justify left bottom) hide)
    )
    (property "Manufacturer" "Molex" (at 168.91 228.6 0)
      (effects (font (size 1.27 1.27) (thickness 0.15)) (justify left bottom) hide)
    )
    (property "MPN" "504050-0291" (at 166.37 222.25 0)
      (effects (font (size 1.27 1.27) (thickness 0.15)) (justify left))
    )
    (property "Author" "Antmicro" (at 168.91 233.68 0)
      (effects (font (size 1.27 1.27) (thickness 0.15)) (justify left bottom) hide)
    )
    (property "License" "Apache-2.0" (at 168.91 236.22 0)
      (effects (font (size 1.27 1.27) (thickness 0.15)) (justify left bottom) hide)
    )
    (pin "SH")
    (pin "1")
    (pin "2")
    (pin "SH")
    (instances
      (project "ecp5-dc-scm"
        (path ""
          (reference "J18") (unit 1)
        )
      )
    )
  )

  (symbol (lib_id "antmicropower:PWR_FLAG") (at 48.26 49.53 0) (unit 1)
    (in_bom yes) (on_board yes) (dnp no)
    (property "Reference" "#FLG026" (at 48.26 47.625 0)
      (effects (font (size 1.27 1.27)) hide)
    )
    (property "Value" "PWR_FLAG" (at 48.26 45.72 0)
      (effects (font (size 1.27 1.27)))
    )
    (property "Footprint" "" (at 48.26 49.53 0)
      (effects (font (size 1.27 1.27)) hide)
    )
    (property "Datasheet" "" (at 48.26 49.53 0)
      (effects (font (size 1.27 1.27)) hide)
    )
    (pin "1")
    (instances
      (project "ecp5-dc-scm"
        (path ""
          (reference "#FLG026") (unit 1)
        )
      )
    )
  )

  (symbol (lib_name "LED_G_0603_LG_L29K-G2J1-24-Z_1") (lib_id "antmicroLEDIndicationDiscrete:LED_G_0603_LG_L29K-G2J1-24-Z") (at 273.05 69.85 180) (unit 1)
    (in_bom yes) (on_board yes) (dnp no)
    (property "Reference" "D13" (at 270.51 67.31 0)
      (effects (font (size 1.27 1.27) (thickness 0.15)))
    )
    (property "Value" "LED_G_0603_LG_L29K-G2J1-24-Z" (at 252.73 62.23 0)
      (effects (font (size 1.27 1.27) (thickness 0.15)) (justify left bottom) hide)
    )
    (property "Footprint" "antmicro-footprints:LED_0603_1608Metric_G" (at 252.73 59.69 0)
      (effects (font (size 1.27 1.27) (thickness 0.15)) (justify left bottom) hide)
    )
    (property "Datasheet" "https://look.ams-osram.com/m/19ee86b3ae0ee95b/original/LG-L29K.pdf" (at 252.73 57.15 0)
      (effects (font (size 1.27 1.27) (thickness 0.15)) (justify left bottom) hide)
    )
    (property "MPN" "LG L29K-G2J1-24-Z" (at 252.73 54.61 0)
      (effects (font (size 1.27 1.27) (thickness 0.15)) (justify left bottom) hide)
    )
    (property "Manufacturer" "OSRAM" (at 252.73 52.07 0)
      (effects (font (size 1.27 1.27) (thickness 0.15)) (justify left bottom) hide)
    )
    (property "Color" "Green" (at 270.51 73.66 0)
      (effects (font (size 1.27 1.27)))
    )
    (property "Author" "Antmicro" (at 252.73 49.53 0)
      (effects (font (size 1.27 1.27) (thickness 0.15)) (justify left bottom) hide)
    )
    (property "License" "Apache-2.0" (at 252.73 46.99 0)
      (effects (font (size 1.27 1.27) (thickness 0.15)) (justify left bottom) hide)
    )
    (pin "1")
    (pin "2")
    (instances
      (project "ecp5-dc-scm"
        (path ""
          (reference "D13") (unit 1)
        )
      )
    )
  )

  (symbol (lib_id "antmicroTestPoints:TP_1mm_SMD") (at 198.12 123.19 90) (unit 1)
    (in_bom no) (on_board yes) (dnp no)
    (property "Reference" "TP7" (at 199.39 118.11 90)
      (effects (font (size 1.27 1.27) (thickness 0.15)) (justify left))
    )
    (property "Value" "TP_1mm_SMD" (at 205.74 107.95 0)
      (effects (font (size 1.27 1.27) (thickness 0.15)) (justify left bottom) hide)
    )
    (property "Footprint" "antmicro-footprints:TP_SMD_1mm" (at 208.28 107.95 0)
      (effects (font (size 1.27 1.27) (thickness 0.15)) (justify left bottom) hide)
    )
    (property "Datasheet" "" (at 210.82 105.41 0)
      (effects (font (size 1.27 1.27) (thickness 0.15)) (justify left bottom) hide)
    )
    (property "MPN" "" (at 198.12 123.19 0)
      (effects (font (size 1.27 1.27)) hide)
    )
    (property "Manufacturer" "" (at 198.12 123.19 0)
      (effects (font (size 1.27 1.27)) hide)
    )
    (property "Author" "Antmicro" (at 213.36 107.95 0)
      (effects (font (size 1.27 1.27) (thickness 0.15)) (justify left bottom) hide)
    )
    (property "License" "Apache-2.0" (at 215.9 107.95 0)
      (effects (font (size 1.27 1.27) (thickness 0.15)) (justify left bottom) hide)
    )
    (pin "1")
    (instances
      (project "ecp5-dc-scm"
        (path ""
          (reference "TP7") (unit 1)
        )
      )
    )
  )

  (symbol (lib_id "antmicropower:PWR_FLAG") (at 53.34 68.58 0) (unit 1)
    (in_bom yes) (on_board yes) (dnp no)
    (property "Reference" "#FLG024" (at 53.34 66.675 0)
      (effects (font (size 1.27 1.27)) hide)
    )
    (property "Value" "PWR_FLAG" (at 53.34 64.77 0)
      (effects (font (size 1.27 1.27)))
    )
    (property "Footprint" "" (at 53.34 68.58 0)
      (effects (font (size 1.27 1.27)) hide)
    )
    (property "Datasheet" "" (at 53.34 68.58 0)
      (effects (font (size 1.27 1.27)) hide)
    )
    (pin "1")
    (instances
      (project "ecp5-dc-scm"
        (path ""
          (reference "#FLG024") (unit 1)
        )
      )
    )
  )

  (symbol (lib_id "antmicroTestPoints:TP_1mm_SMD") (at 115.57 53.34 180) (unit 1)
    (in_bom no) (on_board yes) (dnp no)
    (property "Reference" "TP6" (at 111.76 53.34 0)
      (effects (font (size 1.27 1.27) (thickness 0.15)) (justify left))
    )
    (property "Value" "TP_1mm_SMD" (at 100.33 45.72 0)
      (effects (font (size 1.27 1.27) (thickness 0.15)) (justify left bottom) hide)
    )
    (property "Footprint" "antmicro-footprints:TP_SMD_1mm" (at 100.33 43.18 0)
      (effects (font (size 1.27 1.27) (thickness 0.15)) (justify left bottom) hide)
    )
    (property "Datasheet" "" (at 97.79 40.64 0)
      (effects (font (size 1.27 1.27) (thickness 0.15)) (justify left bottom) hide)
    )
    (property "MPN" "" (at 115.57 53.34 0)
      (effects (font (size 1.27 1.27)) hide)
    )
    (property "Manufacturer" "" (at 115.57 53.34 0)
      (effects (font (size 1.27 1.27)) hide)
    )
    (property "Author" "Antmicro" (at 100.33 38.1 0)
      (effects (font (size 1.27 1.27) (thickness 0.15)) (justify left bottom) hide)
    )
    (property "License" "Apache-2.0" (at 100.33 35.56 0)
      (effects (font (size 1.27 1.27) (thickness 0.15)) (justify left bottom) hide)
    )
    (pin "1")
    (instances
      (project "ecp5-dc-scm"
        (path ""
          (reference "TP6") (unit 1)
        )
      )
    )
  )

  (symbol (lib_id "antmicropower:PWR_FLAG") (at 397.51 35.56 0) (unit 1)
    (in_bom yes) (on_board yes) (dnp no)
    (property "Reference" "#FLG016" (at 397.51 33.655 0)
      (effects (font (size 1.27 1.27)) hide)
    )
    (property "Value" "PWR_FLAG" (at 397.51 31.75 0)
      (effects (font (size 1.27 1.27)))
    )
    (property "Footprint" "" (at 397.51 35.56 0)
      (effects (font (size 1.27 1.27)) hide)
    )
    (property "Datasheet" "" (at 397.51 35.56 0)
      (effects (font (size 1.27 1.27)) hide)
    )
    (pin "1")
    (instances
      (project "ecp5-dc-scm"
        (path ""
          (reference "#FLG016") (unit 1)
        )
      )
    )
  )

  (symbol (lib_id "antmicroTestPoints:TP_1mm_SMD") (at 152.4 50.8 0) (unit 1)
    (in_bom no) (on_board yes) (dnp no)
    (property "Reference" "TP12" (at 156.21 50.8 0)
      (effects (font (size 1.27 1.27) (thickness 0.15)) (justify left))
    )
    (property "Value" "TP_1mm_SMD" (at 167.64 58.42 0)
      (effects (font (size 1.27 1.27) (thickness 0.15)) (justify left bottom) hide)
    )
    (property "Footprint" "antmicro-footprints:TP_SMD_1mm" (at 167.64 60.96 0)
      (effects (font (size 1.27 1.27) (thickness 0.15)) (justify left bottom) hide)
    )
    (property "Datasheet" "" (at 170.18 63.5 0)
      (effects (font (size 1.27 1.27) (thickness 0.15)) (justify left bottom) hide)
    )
    (property "MPN" "" (at 152.4 50.8 0)
      (effects (font (size 1.27 1.27)) hide)
    )
    (property "Manufacturer" "" (at 152.4 50.8 0)
      (effects (font (size 1.27 1.27)) hide)
    )
    (property "Author" "Antmicro" (at 167.64 66.04 0)
      (effects (font (size 1.27 1.27) (thickness 0.15)) (justify left bottom) hide)
    )
    (property "License" "Apache-2.0" (at 167.64 68.58 0)
      (effects (font (size 1.27 1.27) (thickness 0.15)) (justify left bottom) hide)
    )
    (pin "1")
    (instances
      (project "ecp5-dc-scm"
        (path ""
          (reference "TP12") (unit 1)
        )
      )
    )
  )

  (symbol (lib_id "antmicropower:PWR_FLAG") (at 396.24 82.55 0) (unit 1)
    (in_bom yes) (on_board yes) (dnp no)
    (property "Reference" "#FLG01" (at 396.24 80.645 0)
      (effects (font (size 1.27 1.27)) hide)
    )
    (property "Value" "PWR_FLAG" (at 396.24 78.74 0)
      (effects (font (size 1.27 1.27)))
    )
    (property "Footprint" "" (at 396.24 82.55 0)
      (effects (font (size 1.27 1.27)) hide)
    )
    (property "Datasheet" "" (at 396.24 82.55 0)
      (effects (font (size 1.27 1.27)) hide)
    )
    (pin "1")
    (instances
      (project "ecp5-dc-scm"
        (path ""
          (reference "#FLG01") (unit 1)
        )
      )
    )
  )

  (symbol (lib_id "antmicropower:PWR_FLAG") (at 209.55 52.07 0) (unit 1)
    (in_bom yes) (on_board yes) (dnp no)
    (property "Reference" "#FLG023" (at 209.55 50.165 0)
      (effects (font (size 1.27 1.27)) hide)
    )
    (property "Value" "PWR_FLAG" (at 209.55 48.26 0)
      (effects (font (size 1.27 1.27)))
    )
    (property "Footprint" "" (at 209.55 52.07 0)
      (effects (font (size 1.27 1.27)) hide)
    )
    (property "Datasheet" "" (at 209.55 52.07 0)
      (effects (font (size 1.27 1.27)) hide)
    )
    (pin "1")
    (instances
      (project "ecp5-dc-scm"
        (path ""
          (reference "#FLG023") (unit 1)
        )
      )
    )
  )

  (symbol (lib_name "LED_G_0603_LG_L29K-G2J1-24-Z_1") (lib_id "antmicroLEDIndicationDiscrete:LED_G_0603_LG_L29K-G2J1-24-Z") (at 273.05 33.02 180) (unit 1)
    (in_bom yes) (on_board yes) (dnp no)
    (property "Reference" "D12" (at 270.51 30.48 0)
      (effects (font (size 1.27 1.27) (thickness 0.15)))
    )
    (property "Value" "LED_G_0603_LG_L29K-G2J1-24-Z" (at 252.73 25.4 0)
      (effects (font (size 1.27 1.27) (thickness 0.15)) (justify left bottom) hide)
    )
    (property "Footprint" "antmicro-footprints:LED_0603_1608Metric_G" (at 252.73 22.86 0)
      (effects (font (size 1.27 1.27) (thickness 0.15)) (justify left bottom) hide)
    )
    (property "Datasheet" "https://look.ams-osram.com/m/19ee86b3ae0ee95b/original/LG-L29K.pdf" (at 252.73 20.32 0)
      (effects (font (size 1.27 1.27) (thickness 0.15)) (justify left bottom) hide)
    )
    (property "MPN" "LG L29K-G2J1-24-Z" (at 252.73 17.78 0)
      (effects (font (size 1.27 1.27) (thickness 0.15)) (justify left bottom) hide)
    )
    (property "Manufacturer" "OSRAM" (at 252.73 15.24 0)
      (effects (font (size 1.27 1.27) (thickness 0.15)) (justify left bottom) hide)
    )
    (property "Color" "Green" (at 270.51 36.83 0)
      (effects (font (size 1.27 1.27)))
    )
    (property "Author" "Antmicro" (at 252.73 12.7 0)
      (effects (font (size 1.27 1.27) (thickness 0.15)) (justify left bottom) hide)
    )
    (property "License" "Apache-2.0" (at 252.73 10.16 0)
      (effects (font (size 1.27 1.27) (thickness 0.15)) (justify left bottom) hide)
    )
    (pin "1")
    (pin "2")
    (instances
      (project "ecp5-dc-scm"
        (path ""
          (reference "D12") (unit 1)
        )
      )
    )
  )

  (symbol (lib_id "antmicroResistors0402:R_316k_0402") (at 373.38 44.45 90) (unit 1)
    (in_bom yes) (on_board yes) (dnp no) (fields_autoplaced)
    (property "Reference" "R45" (at 375.92 40.64 90)
      (effects (font (size 1.524 1.524)) (justify right))
    )
    (property "Value" "R_316k_0402" (at 377.19 44.45 0)
      (effects (font (size 1.524 1.524)) hide)
    )
    (property "Footprint" "antmicro-footprints:R_0402_1005Metric" (at 368.3 39.37 0)
      (effects (font (size 1.524 1.524)) (justify left) hide)
    )
    (property "Datasheet" "https://www.bourns.com/docs/product-datasheets/cr.pdf" (at 373.38 44.45 0)
      (effects (font (size 1.27 1.27)) hide)
    )
    (property "Manufacturer" "Bourns" (at 363.22 39.37 0)
      (effects (font (size 1.524 1.524)) (justify left) hide)
    )
    (property "MPN" "CR0402-FX-3163GLF" (at 365.76 39.37 0)
      (effects (font (size 1.524 1.524)) (justify left) hide)
    )
    (property "Val" "316k" (at 375.92 43.18 90)
      (effects (font (size 1.27 1.27)) (justify right))
    )
    (property "License" "Apache-2.0" (at 398.78 24.13 0)
      (effects (font (size 1.27 1.27) (thickness 0.15)) (justify left bottom) hide)
    )
    (property "Author" "Antmicro" (at 401.32 24.13 0)
      (effects (font (size 1.27 1.27) (thickness 0.15)) (justify left bottom) hide)
    )
    (property "Tolerance" "1%" (at 383.54 24.13 0)
      (effects (font (size 1.27 1.27)) (justify left bottom) hide)
    )
    (property "Public" "False" (at 403.86 24.13 0)
      (effects (font (size 1.27 1.27)) (justify left bottom) hide)
    )
    (pin "1")
    (pin "2")
    (instances
      (project "ecp5-dc-scm"
        (path ""
          (reference "R45") (unit 1)
        )
      )
    )
  )

  (symbol (lib_id "antmicropower:GND") (at 109.22 72.39 0) (unit 1)
    (in_bom yes) (on_board yes) (dnp no)
    (property "Reference" "#PWR0109" (at 109.22 78.74 0)
      (effects (font (size 1.27 1.27)) hide)
    )
    (property "Value" "GND" (at 109.347 76.7842 0)
      (effects (font (size 1.27 1.27)))
    )
    (property "Footprint" "" (at 109.22 72.39 0)
      (effects (font (size 1.27 1.27)) hide)
    )
    (property "Datasheet" "" (at 109.22 72.39 0)
      (effects (font (size 1.27 1.27)) hide)
    )
    (property "Author" "Antmicro" (at 118.11 80.01 0)
      (effects (font (size 1.27 1.27) (thickness 0.15)) (justify left bottom) hide)
    )
    (property "License" "Apache-2.0" (at 118.11 82.55 0)
      (effects (font (size 1.27 1.27) (thickness 0.15)) (justify left bottom) hide)
    )
    (pin "1")
    (instances
      (project "ecp5-dc-scm"
        (path ""
          (reference "#PWR0109") (unit 1)
        )
      )
    )
  )

  (symbol (lib_id "antmicroTestPoints:TP_1mm_SMD") (at 388.62 130.81 90) (unit 1)
    (in_bom no) (on_board yes) (dnp no)
    (property "Reference" "TP9" (at 389.89 125.73 90)
      (effects (font (size 1.27 1.27) (thickness 0.15)) (justify left))
    )
    (property "Value" "TP_1mm_SMD" (at 396.24 115.57 0)
      (effects (font (size 1.27 1.27) (thickness 0.15)) (justify left bottom) hide)
    )
    (property "Footprint" "antmicro-footprints:TP_SMD_1mm" (at 398.78 115.57 0)
      (effects (font (size 1.27 1.27) (thickness 0.15)) (justify left bottom) hide)
    )
    (property "Datasheet" "" (at 401.32 113.03 0)
      (effects (font (size 1.27 1.27) (thickness 0.15)) (justify left bottom) hide)
    )
    (property "MPN" "" (at 388.62 130.81 0)
      (effects (font (size 1.27 1.27)) hide)
    )
    (property "Manufacturer" "" (at 388.62 130.81 0)
      (effects (font (size 1.27 1.27)) hide)
    )
    (property "Author" "Antmicro" (at 403.86 115.57 0)
      (effects (font (size 1.27 1.27) (thickness 0.15)) (justify left bottom) hide)
    )
    (property "License" "Apache-2.0" (at 406.4 115.57 0)
      (effects (font (size 1.27 1.27) (thickness 0.15)) (justify left bottom) hide)
    )
    (pin "1")
    (instances
      (project "ecp5-dc-scm"
        (path ""
          (reference "TP9") (unit 1)
        )
      )
    )
  )

  (symbol (lib_id "antmicropower:GND") (at 48.26 50.8 0) (unit 1)
    (in_bom yes) (on_board yes) (dnp no)
    (property "Reference" "#PWR042" (at 48.26 57.15 0)
      (effects (font (size 1.27 1.27)) hide)
    )
    (property "Value" "GND" (at 48.387 55.1942 0)
      (effects (font (size 1.27 1.27)))
    )
    (property "Footprint" "" (at 48.26 50.8 0)
      (effects (font (size 1.27 1.27)) hide)
    )
    (property "Datasheet" "" (at 48.26 50.8 0)
      (effects (font (size 1.27 1.27)) hide)
    )
    (property "Author" "Antmicro" (at 57.15 58.42 0)
      (effects (font (size 1.27 1.27) (thickness 0.15)) (justify left bottom) hide)
    )
    (property "License" "Apache-2.0" (at 57.15 60.96 0)
      (effects (font (size 1.27 1.27) (thickness 0.15)) (justify left bottom) hide)
    )
    (pin "1")
    (instances
      (project "ecp5-dc-scm"
        (path ""
          (reference "#PWR042") (unit 1)
        )
      )
    )
  )

  (symbol (lib_name "LED_G_0603_LG_L29K-G2J1-24-Z_1") (lib_id "antmicroLEDIndicationDiscrete:LED_G_0603_LG_L29K-G2J1-24-Z") (at 273.05 256.54 180) (unit 1)
    (in_bom yes) (on_board yes) (dnp no)
    (property "Reference" "D11" (at 270.51 254 0)
      (effects (font (size 1.27 1.27) (thickness 0.15)))
    )
    (property "Value" "LED_G_0603_LG_L29K-G2J1-24-Z" (at 252.73 248.92 0)
      (effects (font (size 1.27 1.27) (thickness 0.15)) (justify left bottom) hide)
    )
    (property "Footprint" "antmicro-footprints:LED_0603_1608Metric_G" (at 252.73 246.38 0)
      (effects (font (size 1.27 1.27) (thickness 0.15)) (justify left bottom) hide)
    )
    (property "Datasheet" "https://look.ams-osram.com/m/19ee86b3ae0ee95b/original/LG-L29K.pdf" (at 252.73 243.84 0)
      (effects (font (size 1.27 1.27) (thickness 0.15)) (justify left bottom) hide)
    )
    (property "MPN" "LG L29K-G2J1-24-Z" (at 252.73 241.3 0)
      (effects (font (size 1.27 1.27) (thickness 0.15)) (justify left bottom) hide)
    )
    (property "Manufacturer" "OSRAM" (at 252.73 238.76 0)
      (effects (font (size 1.27 1.27) (thickness 0.15)) (justify left bottom) hide)
    )
    (property "Color" "Green" (at 270.51 260.35 0)
      (effects (font (size 1.27 1.27)))
    )
    (property "Author" "Antmicro" (at 252.73 236.22 0)
      (effects (font (size 1.27 1.27) (thickness 0.15)) (justify left bottom) hide)
    )
    (property "License" "Apache-2.0" (at 252.73 233.68 0)
      (effects (font (size 1.27 1.27) (thickness 0.15)) (justify left bottom) hide)
    )
    (pin "1")
    (pin "2")
    (instances
      (project "ecp5-dc-scm"
        (path ""
          (reference "D11") (unit 1)
        )
      )
    )
  )

  (symbol (lib_id "antmicroTestPoints:TP_1mm_SMD") (at 388.62 222.25 90) (unit 1)
    (in_bom no) (on_board yes) (dnp no)
    (property "Reference" "TP11" (at 391.16 217.17 90)
      (effects (font (size 1.27 1.27) (thickness 0.15)) (justify left))
    )
    (property "Value" "TP_1mm_SMD" (at 396.24 207.01 0)
      (effects (font (size 1.27 1.27) (thickness 0.15)) (justify left bottom) hide)
    )
    (property "Footprint" "antmicro-footprints:TP_SMD_1mm" (at 398.78 207.01 0)
      (effects (font (size 1.27 1.27) (thickness 0.15)) (justify left bottom) hide)
    )
    (property "Datasheet" "" (at 401.32 204.47 0)
      (effects (font (size 1.27 1.27) (thickness 0.15)) (justify left bottom) hide)
    )
    (property "MPN" "" (at 388.62 222.25 0)
      (effects (font (size 1.27 1.27)) hide)
    )
    (property "Manufacturer" "" (at 388.62 222.25 0)
      (effects (font (size 1.27 1.27)) hide)
    )
    (property "Author" "Antmicro" (at 403.86 207.01 0)
      (effects (font (size 1.27 1.27) (thickness 0.15)) (justify left bottom) hide)
    )
    (property "License" "Apache-2.0" (at 406.4 207.01 0)
      (effects (font (size 1.27 1.27) (thickness 0.15)) (justify left bottom) hide)
    )
    (pin "1")
    (instances
      (project "ecp5-dc-scm"
        (path ""
          (reference "TP11") (unit 1)
        )
      )
    )
  )

  (symbol (lib_name "LED_G_0603_LG_L29K-G2J1-24-Z_1") (lib_id "antmicroLEDIndicationDiscrete:LED_G_0603_LG_L29K-G2J1-24-Z") (at 273.05 146.05 180) (unit 1)
    (in_bom yes) (on_board yes) (dnp no)
    (property "Reference" "D9" (at 270.51 143.51 0)
      (effects (font (size 1.27 1.27) (thickness 0.15)))
    )
    (property "Value" "LED_G_0603_LG_L29K-G2J1-24-Z" (at 252.73 138.43 0)
      (effects (font (size 1.27 1.27) (thickness 0.15)) (justify left bottom) hide)
    )
    (property "Footprint" "antmicro-footprints:LED_0603_1608Metric_G" (at 252.73 135.89 0)
      (effects (font (size 1.27 1.27) (thickness 0.15)) (justify left bottom) hide)
    )
    (property "Datasheet" "https://look.ams-osram.com/m/19ee86b3ae0ee95b/original/LG-L29K.pdf" (at 252.73 133.35 0)
      (effects (font (size 1.27 1.27) (thickness 0.15)) (justify left bottom) hide)
    )
    (property "MPN" "LG L29K-G2J1-24-Z" (at 252.73 130.81 0)
      (effects (font (size 1.27 1.27) (thickness 0.15)) (justify left bottom) hide)
    )
    (property "Manufacturer" "OSRAM" (at 252.73 128.27 0)
      (effects (font (size 1.27 1.27) (thickness 0.15)) (justify left bottom) hide)
    )
    (property "Color" "Green" (at 270.51 149.86 0)
      (effects (font (size 1.27 1.27)))
    )
    (property "Author" "Antmicro" (at 252.73 125.73 0)
      (effects (font (size 1.27 1.27) (thickness 0.15)) (justify left bottom) hide)
    )
    (property "License" "Apache-2.0" (at 252.73 123.19 0)
      (effects (font (size 1.27 1.27) (thickness 0.15)) (justify left bottom) hide)
    )
    (pin "1")
    (pin "2")
    (instances
      (project "ecp5-dc-scm"
        (path ""
          (reference "D9") (unit 1)
        )
      )
    )
  )

  (symbol (lib_id "antmicroWire2BoardConnectors:Molex_Pico-Lock_1x2_504050-0291") (at 38.1 38.1 0) (mirror y) (unit 1)
    (in_bom yes) (on_board yes) (dnp no) (fields_autoplaced)
    (property "Reference" "J8" (at 34.29 31.75 0)
      (effects (font (size 1.27 1.27) (thickness 0.15)))
    )
    (property "Value" "Molex_Pico-Lock_1x2_504050-0291" (at 29.21 40.64 0)
      (effects (font (size 1.27 1.27) (thickness 0.15)) (justify left bottom) hide)
    )
    (property "Footprint" "antmicro-footprints:Conn_Molex_Pico-Lock_1x2_504050-0291" (at 29.21 43.18 0)
      (effects (font (size 1.27 1.27) (thickness 0.15)) (justify left bottom) hide)
    )
    (property "Datasheet" "https://tools.molex.com/pdm_docs/ps/PS-504051-001-001.pdf" (at 29.21 45.72 0)
      (effects (font (size 1.27 1.27) (thickness 0.15)) (justify left bottom) hide)
    )
    (property "Manufacturer" "Molex" (at 29.21 48.26 0)
      (effects (font (size 1.27 1.27) (thickness 0.15)) (justify left bottom) hide)
    )
    (property "MPN" "504050-0291" (at 34.29 34.29 0)
      (effects (font (size 1.27 1.27) (thickness 0.15)))
    )
    (property "Author" "Antmicro" (at 29.21 53.34 0)
      (effects (font (size 1.27 1.27) (thickness 0.15)) (justify left bottom) hide)
    )
    (property "License" "Apache-2.0" (at 29.21 55.88 0)
      (effects (font (size 1.27 1.27) (thickness 0.15)) (justify left bottom) hide)
    )
    (pin "SH")
    (pin "2")
    (pin "1")
    (pin "SH")
    (instances
      (project "ecp5-dc-scm"
        (path ""
          (reference "J8") (unit 1)
        )
      )
    )
  )

  (symbol (lib_id "antmicroTestPoints:TP_1mm_SMD") (at 387.35 82.55 90) (unit 1)
    (in_bom no) (on_board yes) (dnp no)
    (property "Reference" "TP8" (at 388.62 77.47 90)
      (effects (font (size 1.27 1.27) (thickness 0.15)) (justify left))
    )
    (property "Value" "TP_1mm_SMD" (at 394.97 67.31 0)
      (effects (font (size 1.27 1.27) (thickness 0.15)) (justify left bottom) hide)
    )
    (property "Footprint" "antmicro-footprints:TP_SMD_1mm" (at 397.51 67.31 0)
      (effects (font (size 1.27 1.27) (thickness 0.15)) (justify left bottom) hide)
    )
    (property "Datasheet" "" (at 400.05 64.77 0)
      (effects (font (size 1.27 1.27) (thickness 0.15)) (justify left bottom) hide)
    )
    (property "MPN" "" (at 387.35 82.55 0)
      (effects (font (size 1.27 1.27)) hide)
    )
    (property "Manufacturer" "" (at 387.35 82.55 0)
      (effects (font (size 1.27 1.27)) hide)
    )
    (property "Author" "Antmicro" (at 402.59 67.31 0)
      (effects (font (size 1.27 1.27) (thickness 0.15)) (justify left bottom) hide)
    )
    (property "License" "Apache-2.0" (at 405.13 67.31 0)
      (effects (font (size 1.27 1.27) (thickness 0.15)) (justify left bottom) hide)
    )
    (pin "1")
    (instances
      (project "ecp5-dc-scm"
        (path ""
          (reference "TP8") (unit 1)
        )
      )
    )
  )

  (symbol (lib_id "antmicropower:PWR_FLAG") (at 397.51 130.81 0) (unit 1)
    (in_bom yes) (on_board yes) (dnp no)
    (property "Reference" "#FLG015" (at 397.51 128.905 0)
      (effects (font (size 1.27 1.27)) hide)
    )
    (property "Value" "PWR_FLAG" (at 397.51 127 0)
      (effects (font (size 1.27 1.27)))
    )
    (property "Footprint" "" (at 397.51 130.81 0)
      (effects (font (size 1.27 1.27)) hide)
    )
    (property "Datasheet" "" (at 397.51 130.81 0)
      (effects (font (size 1.27 1.27)) hide)
    )
    (pin "1")
    (instances
      (project "ecp5-dc-scm"
        (path ""
          (reference "#FLG015") (unit 1)
        )
      )
    )
  )

  (symbol (lib_id "antmicroCapacitors0402:C_10n_0402") (at 113.03 68.58 90) (unit 1)
    (in_bom yes) (on_board yes) (dnp no)
    (property "Reference" "C59" (at 116.84 64.77 90)
      (effects (font (size 1.524 1.524)))
    )
    (property "Value" "C_10n_0402" (at 116.84 68.58 0)
      (effects (font (size 1.524 1.524)) hide)
    )
    (property "Footprint" "antmicro-footprints:C_0402_1005Metric" (at 107.95 63.5 0)
      (effects (font (size 1.524 1.524)) (justify left) hide)
    )
    (property "Datasheet" "https://www.murata.com/products/productdetail?partno=GRM155R71H103KA88%23" (at 113.03 68.58 0)
      (effects (font (size 1.27 1.27)) hide)
    )
    (property "Manufacturer" "Murata" (at 102.87 63.5 0)
      (effects (font (size 1.524 1.524)) (justify left) hide)
    )
    (property "MPN" "GRM155R71H103KA88D" (at 105.41 63.5 0)
      (effects (font (size 1.524 1.524)) (justify left) hide)
    )
    (property "Val" "10n" (at 116.84 67.31 90)
      (effects (font (size 1.27 1.27)))
    )
    (property "License" "Apache-2.0" (at 135.89 48.26 0)
      (effects (font (size 1.27 1.27) (thickness 0.15)) (justify left bottom) hide)
    )
    (property "Author" "Antmicro" (at 138.43 48.26 0)
      (effects (font (size 1.27 1.27) (thickness 0.15)) (justify left bottom) hide)
    )
    (property "Voltage" "50V" (at 140.97 48.26 0)
      (effects (font (size 1.27 1.27)) (justify left bottom) hide)
    )
    (property "Dielectric" "X7R" (at 143.51 48.26 0)
      (effects (font (size 1.27 1.27)) (justify left bottom) hide)
    )
    (property "Public" "False" (at 146.05 48.26 0)
      (effects (font (size 1.27 1.27)) (justify left bottom) hide)
    )
    (pin "1")
    (pin "2")
    (instances
      (project "ecp5-dc-scm"
        (path ""
          (reference "C59") (unit 1)
        )
      )
    )
  )

  (symbol (lib_id "antmicropower:GND") (at 55.88 238.76 0) (unit 1)
    (in_bom yes) (on_board yes) (dnp no)
    (property "Reference" "#PWR0121" (at 55.88 245.11 0)
      (effects (font (size 1.27 1.27)) hide)
    )
    (property "Value" "GND" (at 56.007 243.1542 0)
      (effects (font (size 1.27 1.27)))
    )
    (property "Footprint" "" (at 55.88 238.76 0)
      (effects (font (size 1.27 1.27)) hide)
    )
    (property "Datasheet" "" (at 55.88 238.76 0)
      (effects (font (size 1.27 1.27)) hide)
    )
    (property "Author" "Antmicro" (at 64.77 246.38 0)
      (effects (font (size 1.27 1.27) (thickness 0.15)) (justify left bottom) hide)
    )
    (property "License" "Apache-2.0" (at 64.77 248.92 0)
      (effects (font (size 1.27 1.27) (thickness 0.15)) (justify left bottom) hide)
    )
    (pin "1")
    (instances
      (project "ecp5-dc-scm"
        (path ""
          (reference "#PWR0121") (unit 1)
        )
      )
    )
  )

  (symbol (lib_name "LED_G_0603_LG_L29K-G2J1-24-Z_1") (lib_id "antmicroLEDIndicationDiscrete:LED_G_0603_LG_L29K-G2J1-24-Z") (at 273.05 107.95 180) (unit 1)
    (in_bom yes) (on_board yes) (dnp no)
    (property "Reference" "D8" (at 270.51 105.41 0)
      (effects (font (size 1.27 1.27) (thickness 0.15)))
    )
    (property "Value" "LED_G_0603_LG_L29K-G2J1-24-Z" (at 252.73 100.33 0)
      (effects (font (size 1.27 1.27) (thickness 0.15)) (justify left bottom) hide)
    )
    (property "Footprint" "antmicro-footprints:LED_0603_1608Metric_G" (at 252.73 97.79 0)
      (effects (font (size 1.27 1.27) (thickness 0.15)) (justify left bottom) hide)
    )
    (property "Datasheet" "https://look.ams-osram.com/m/19ee86b3ae0ee95b/original/LG-L29K.pdf" (at 252.73 95.25 0)
      (effects (font (size 1.27 1.27) (thickness 0.15)) (justify left bottom) hide)
    )
    (property "MPN" "LG L29K-G2J1-24-Z" (at 252.73 92.71 0)
      (effects (font (size 1.27 1.27) (thickness 0.15)) (justify left bottom) hide)
    )
    (property "Manufacturer" "OSRAM" (at 252.73 90.17 0)
      (effects (font (size 1.27 1.27) (thickness 0.15)) (justify left bottom) hide)
    )
    (property "Color" "Green" (at 270.51 111.76 0)
      (effects (font (size 1.27 1.27)))
    )
    (property "Author" "Antmicro" (at 252.73 87.63 0)
      (effects (font (size 1.27 1.27) (thickness 0.15)) (justify left bottom) hide)
    )
    (property "License" "Apache-2.0" (at 252.73 85.09 0)
      (effects (font (size 1.27 1.27) (thickness 0.15)) (justify left bottom) hide)
    )
    (pin "1")
    (pin "2")
    (instances
      (project "ecp5-dc-scm"
        (path ""
          (reference "D8") (unit 1)
        )
      )
    )
  )

  (symbol (lib_id "antmicropower:GND") (at 186.69 67.31 0) (unit 1)
    (in_bom yes) (on_board yes) (dnp no)
    (property "Reference" "#PWR075" (at 186.69 73.66 0)
      (effects (font (size 1.27 1.27)) hide)
    )
    (property "Value" "GND" (at 186.817 71.7042 0)
      (effects (font (size 1.27 1.27)))
    )
    (property "Footprint" "" (at 186.69 67.31 0)
      (effects (font (size 1.27 1.27)) hide)
    )
    (property "Datasheet" "" (at 186.69 67.31 0)
      (effects (font (size 1.27 1.27)) hide)
    )
    (property "Author" "Antmicro" (at 195.58 74.93 0)
      (effects (font (size 1.27 1.27) (thickness 0.15)) (justify left bottom) hide)
    )
    (property "License" "Apache-2.0" (at 195.58 77.47 0)
      (effects (font (size 1.27 1.27) (thickness 0.15)) (justify left bottom) hide)
    )
    (pin "1")
    (instances
      (project "ecp5-dc-scm"
        (path ""
          (reference "#PWR075") (unit 1)
        )
      )
    )
  )

  (symbol (lib_id "antmicropower:PWR_FLAG") (at 36.83 68.58 0) (unit 1)
    (in_bom yes) (on_board yes) (dnp no)
    (property "Reference" "#FLG025" (at 36.83 66.675 0)
      (effects (font (size 1.27 1.27)) hide)
    )
    (property "Value" "PWR_FLAG" (at 36.83 64.77 0)
      (effects (font (size 1.27 1.27)))
    )
    (property "Footprint" "" (at 36.83 68.58 0)
      (effects (font (size 1.27 1.27)) hide)
    )
    (property "Datasheet" "" (at 36.83 68.58 0)
      (effects (font (size 1.27 1.27)) hide)
    )
    (pin "1")
    (instances
      (project "ecp5-dc-scm"
        (path ""
          (reference "#FLG025") (unit 1)
        )
      )
    )
  )
)
